FILE_TYPE = MACRO_DRAWING;
SET COLOR_WIRE YELLOW;
SET COLOR_PROP ORANGE;
SET COLOR_DOT WHITE;
SET COLOR_ARC YELLOW;
SET COLOR_BODY GREEN;
SET COLOR_NOTE PURPLE;
SET PROP_DISPLAY VALUE;
SET PAGE_NUMBER P30;
SET PATH_NUMBER P267;
FORCEADD OFFPAGE..4
(4875 4225);
FORCEPROP 2 LAST $XR0 13 
J 0
(5061 4225);
DISPLAY 0.638298 (5061 4225);
PAINT MONO (5061 4225);
FORCEPROP 2 LAST PATH I104
J 0
(5075 4275);
DISPLAY 0.680851 (5075 4275);
DISPLAY INVISIBLE (5075 4275);
FORCEPROP 1 LAST COMMENT_BODY TRUE
J 0
(4850 4125);
DISPLAY 0.872340 (4850 4125);
PAINT PEACH (4850 4125);
DISPLAY INVISIBLE (4850 4125);
FORCEPROP 1 LAST OFFPAGE TRUE
J 0
(5200 4100);
DISPLAY 0.872340 (5200 4100);
PAINT GREEN (5200 4100);
DISPLAY INVISIBLE (5200 4100);
FORCEPROP 2 LAST CDS_LIB standard
J 0
(4875 4225);
DISPLAY 0.808511 (4875 4225);
PAINT MONO (4875 4225);
DISPLAY INVISIBLE (4875 4225);
FORCEADD OFFPAGE..4
(4875 4175);
FORCEPROP 2 LAST $XR0 30 
J 0
(5061 4175);
DISPLAY 0.638298 (5061 4175);
PAINT MONO (5061 4175);
FORCEPROP 2 LAST PATH I105
J 0
(5250 4225);
DISPLAY 0.680851 (5250 4225);
DISPLAY INVISIBLE (5250 4225);
FORCEPROP 1 LAST COMMENT_BODY TRUE
J 0
(4850 4075);
DISPLAY 0.872340 (4850 4075);
PAINT PEACH (4850 4075);
DISPLAY INVISIBLE (4850 4075);
FORCEPROP 1 LAST OFFPAGE TRUE
J 0
(5200 4050);
DISPLAY 0.872340 (5200 4050);
PAINT GREEN (5200 4050);
DISPLAY INVISIBLE (5200 4050);
FORCEPROP 2 LAST CDS_LIB standard
J 0
(4875 4175);
DISPLAY 0.808511 (4875 4175);
PAINT MONO (4875 4175);
DISPLAY INVISIBLE (4875 4175);
FORCEADD OFFPAGE..2
(5000 3250);
FORCEPROP 2 LAST $XR0 13 
J 0
(5189 3250);
DISPLAY 0.638298 (5189 3250);
PAINT MONO (5189 3250);
FORCEPROP 1 LAST COMMENT_BODY TRUE
J 0
(4955 3155);
DISPLAY 0.872340 (4955 3155);
PAINT PEACH (4955 3155);
DISPLAY INVISIBLE (4955 3155);
FORCEPROP 1 LAST OFFPAGE TRUE
J 0
(5325 3125);
DISPLAY 0.872340 (5325 3125);
PAINT GREEN (5325 3125);
DISPLAY INVISIBLE (5325 3125);
FORCEPROP 2 LAST PATH I107
J 0
(5200 3300);
DISPLAY 0.680851 (5200 3300);
DISPLAY INVISIBLE (5200 3300);
FORCEPROP 2 LAST CDS_LIB standard
J 0
(5000 3250);
DISPLAY 0.808511 (5000 3250);
PAINT MONO (5000 3250);
DISPLAY INVISIBLE (5000 3250);
FORCEADD OFFPAGE..2
R 2
(3875 2675);
FORCEPROP 2 LAST $XR0 30 
J 0
(3651 2675);
DISPLAY 0.638298 (3651 2675);
PAINT MONO (3651 2675);
FORCEPROP 2 LAST CDS_LIB standard
J 2
(3875 2675);
DISPLAY 0.808511 (3875 2675);
PAINT MONO (3875 2675);
DISPLAY INVISIBLE (3875 2675);
FORCEPROP 1 LAST OFFPAGE TRUE
J 2
(3550 2550);
DISPLAY 0.872340 (3550 2550);
PAINT GREEN (3550 2550);
DISPLAY INVISIBLE (3550 2550);
FORCEPROP 1 LAST COMMENT_BODY TRUE
J 2
(3920 2580);
DISPLAY 0.872340 (3920 2580);
PAINT PEACH (3920 2580);
DISPLAY INVISIBLE (3920 2580);
FORCEPROP 2 LAST PATH I108
J 2
(3575 2725);
DISPLAY 0.680851 (3575 2725);
DISPLAY INVISIBLE (3575 2725);
FORCEADD UNIVERSAL_GND..1
(4025 3800);
FORCEPROP 3 LASTPIN (4025 3850) SIG_NAME GND\g
J 0
(4035 3860);
DISPLAY 0.659574 (4035 3860);
PAINT MONO (4035 3860);
DISPLAY INVISIBLE (4035 3860);
FORCEPROP 2 LAST CDS_LIB logical_power
J 0
(4025 3800);
DISPLAY INVISIBLE (4025 3800);
FORCEPROP 1 LAST PATH I117
J 0
(4100 3800);
DISPLAY 0.872340 (4100 3800);
PAINT AQUA (4100 3800);
DISPLAY INVISIBLE (4100 3800);
FORCEPROP 1 LAST HDL_POWER GND
J 1
(4050 3725);
DISPLAY 0.702128 (4050 3725);
PAINT GREEN (4050 3725);
DISPLAY INVISIBLE (4050 3725);
FORCEADD OFFPAGE..2
(4625 950);
FORCEPROP 2 LAST $XR0 30 
J 0
(4814 950);
DISPLAY 0.638298 (4814 950);
PAINT MONO (4814 950);
FORCEPROP 2 LAST PATH I142
J 0
(4825 1000);
DISPLAY 0.680851 (4825 1000);
DISPLAY INVISIBLE (4825 1000);
FORCEPROP 1 LAST COMMENT_BODY TRUE
J 0
(4580 855);
DISPLAY 0.872340 (4580 855);
PAINT PEACH (4580 855);
DISPLAY INVISIBLE (4580 855);
FORCEPROP 1 LAST OFFPAGE TRUE
J 0
(4950 825);
DISPLAY 0.872340 (4950 825);
PAINT GREEN (4950 825);
DISPLAY INVISIBLE (4950 825);
FORCEPROP 2 LAST CDS_LIB standard
J 0
(4625 950);
DISPLAY 0.808511 (4625 950);
PAINT MONO (4625 950);
DISPLAY INVISIBLE (4625 950);
FORCEADD OFFPAGE..2
(4625 850);
FORCEPROP 2 LAST $XR0 30 
J 0
(4814 850);
DISPLAY 0.638298 (4814 850);
PAINT MONO (4814 850);
FORCEPROP 2 LAST CDS_LIB standard
J 0
(4625 850);
DISPLAY 0.808511 (4625 850);
PAINT MONO (4625 850);
DISPLAY INVISIBLE (4625 850);
FORCEPROP 1 LAST OFFPAGE TRUE
J 0
(4950 725);
DISPLAY 0.872340 (4950 725);
PAINT GREEN (4950 725);
DISPLAY INVISIBLE (4950 725);
FORCEPROP 1 LAST COMMENT_BODY TRUE
J 0
(4580 755);
DISPLAY 0.872340 (4580 755);
PAINT PEACH (4580 755);
DISPLAY INVISIBLE (4580 755);
FORCEPROP 2 LAST PATH I143
J 0
(4925 900);
DISPLAY 0.680851 (4925 900);
DISPLAY INVISIBLE (4925 900);
FORCEADD Q_RES..2
R 2
(1825 2450);
FORCEPROP 1 LAST PART_NUMBER CS24702FB06
J 2
(1785 2325);
DISPLAY 0.510638 (1785 2325);
PAINT WHITE (1785 2325);
FORCEPROP 1 LAST MATERIAL CHIP
J 2
(1785 2375);
DISPLAY 0.510638 (1785 2375);
PAINT SKYBLUE (1785 2375);
FORCEPROP 1 LAST WATTAGE 1/16W
J 2
(1785 2425);
DISPLAY 0.510638 (1785 2425);
PAINT SKYBLUE (1785 2425);
FORCEPROP 1 LAST TOLERANCE 1%
J 2
(1780 2475);
DISPLAY 0.510638 (1780 2475);
PAINT SKYBLUE (1780 2475);
FORCEPROP 1 LAST VALUE 4.7K
J 2
(1780 2525);
DISPLAY 0.510638 (1780 2525);
PAINT SKYBLUE (1780 2525);
FORCEPROP 1 LAST PACK_TYPE 0402LF
J 2
(1785 2275);
DISPLAY 0.510638 (1785 2275);
PAINT SKYBLUE (1785 2275);
FORCEPROP 1 LAST PATH I146
J 2
(1775 2625);
DISPLAY 0.978723 (1775 2625);
PAINT WHITE (1775 2625);
DISPLAY INVISIBLE (1775 2625);
FORCEPROP 2 LAST SEC_TYPE 0402LF
J 0
(1775 2675);
DISPLAY 0.680851 (1775 2675);
DISPLAY INVISIBLE (1775 2675);
FORCEPROP 2 LAST CDS_LIB pure_quanta
J 2
(1825 2450);
PAINT MONO (1825 2450);
DISPLAY INVISIBLE (1825 2450);
FORCEPROP 1 LAST LOCATION R67
J 2
(1780 2575);
DISPLAY 0.702128 (1780 2575);
PAINT YELLOW (1780 2575);
FORCEPROP 1 LASTPIN (1825 2550) $PN 1
J 2
(1820 2512);
DISPLAY 0.808511 (1820 2512);
PAINT WHITE (1820 2512);
FORCEPROP 1 LASTPIN (1825 2350) $PN 2
J 2
(1820 2360);
DISPLAY 0.808511 (1820 2360);
PAINT WHITE (1820 2360);
FORCEPROP 2 LAST SEC 1
J 0
(1775 2675);
DISPLAY 0.680851 (1775 2675);
PAINT MONO (1775 2675);
DISPLAY INVISIBLE (1775 2675);
FORCEADD Q_RES..1
(3250 850);
FORCEPROP 1 LAST TOLERANCE 1%
J 0
(3475 800);
DISPLAY 0.510638 (3475 800);
PAINT SKYBLUE (3475 800);
FORCEPROP 1 LAST PACK_TYPE 0402LF
J 0
(3300 800);
DISPLAY 0.510638 (3300 800);
PAINT SKYBLUE (3300 800);
FORCEPROP 1 LAST VALUE 33.2
J 0
(3375 850);
DISPLAY 0.510638 (3375 850);
PAINT SKYBLUE (3375 850);
FORCEPROP 1 LAST MATERIAL CHIP
J 0
(3525 850);
DISPLAY 0.510638 (3525 850);
PAINT SKYBLUE (3525 850);
FORCEPROP 1 LAST WATTAGE 1/16W
J 2
(3650 800);
DISPLAY 0.510638 (3650 800);
PAINT SKYBLUE (3650 800);
FORCEPROP 1 LAST PART_NUMBER CS03322FB03
J 0
(3375 900);
DISPLAY 0.510638 (3375 900);
PAINT WHITE (3375 900);
DISPLAY INVISIBLE (3375 900);
FORCEPROP 1 LAST PATH I147
J 0
(3200 1000);
DISPLAY 0.978723 (3200 1000);
PAINT WHITE (3200 1000);
DISPLAY INVISIBLE (3200 1000);
FORCEPROP 2 LAST SEC_TYPE 0402LF
J 0
(3200 1050);
DISPLAY 0.680851 (3200 1050);
DISPLAY INVISIBLE (3200 1050);
FORCEPROP 2 LAST CDS_LIB pure_quanta
J 0
(3250 850);
DISPLAY INVISIBLE (3250 850);
FORCEPROP 1 LAST LOCATION R104
J 0
(2950 850);
DISPLAY 0.702128 (2950 850);
PAINT YELLOW (2950 850);
FORCEPROP 1 LASTPIN (3150 850) $PN 1
J 0
(3162 862);
DISPLAY 0.808511 (3162 862);
PAINT WHITE (3162 862);
FORCEPROP 1 LASTPIN (3350 850) $PN 2
J 0
(3315 860);
DISPLAY 0.808511 (3315 860);
PAINT WHITE (3315 860);
FORCEPROP 2 LAST SEC 1
J 0
(3200 1050);
DISPLAY 0.680851 (3200 1050);
PAINT MONO (3200 1050);
DISPLAY INVISIBLE (3200 1050);
FORCEADD Q_RES..1
(3250 950);
FORCEPROP 1 LAST PACK_TYPE 0402LF
J 0
(3300 900);
DISPLAY 0.510638 (3300 900);
PAINT SKYBLUE (3300 900);
FORCEPROP 1 LAST VALUE 33.2
J 0
(3375 950);
DISPLAY 0.510638 (3375 950);
PAINT SKYBLUE (3375 950);
FORCEPROP 1 LAST MATERIAL CHIP
J 0
(3525 950);
DISPLAY 0.510638 (3525 950);
PAINT SKYBLUE (3525 950);
FORCEPROP 1 LAST WATTAGE 1/16W
J 2
(3650 900);
DISPLAY 0.510638 (3650 900);
PAINT SKYBLUE (3650 900);
FORCEPROP 1 LAST TOLERANCE 1%
J 0
(3475 900);
DISPLAY 0.510638 (3475 900);
PAINT SKYBLUE (3475 900);
FORCEPROP 1 LAST PART_NUMBER CS03322FB03
J 0
(3375 1000);
DISPLAY 0.510638 (3375 1000);
PAINT WHITE (3375 1000);
DISPLAY INVISIBLE (3375 1000);
FORCEPROP 1 LAST PATH I148
J 0
(3200 1100);
DISPLAY 0.978723 (3200 1100);
PAINT WHITE (3200 1100);
DISPLAY INVISIBLE (3200 1100);
FORCEPROP 2 LAST SEC_TYPE 0402LF
J 0
(3200 1150);
DISPLAY 0.680851 (3200 1150);
DISPLAY INVISIBLE (3200 1150);
FORCEPROP 2 LAST CDS_LIB pure_quanta
J 0
(3250 950);
DISPLAY INVISIBLE (3250 950);
FORCEPROP 1 LAST LOCATION R102
J 0
(2950 950);
DISPLAY 0.702128 (2950 950);
PAINT YELLOW (2950 950);
FORCEPROP 1 LASTPIN (3150 950) $PN 1
J 0
(3162 962);
DISPLAY 0.808511 (3162 962);
PAINT WHITE (3162 962);
FORCEPROP 1 LASTPIN (3350 950) $PN 2
J 0
(3315 960);
DISPLAY 0.808511 (3315 960);
PAINT WHITE (3315 960);
FORCEPROP 2 LAST SEC 1
J 0
(3200 1150);
DISPLAY 0.680851 (3200 1150);
PAINT MONO (3200 1150);
DISPLAY INVISIBLE (3200 1150);
FORCEADD Q_CAP..1
(2050 1300);
FORCEPROP 1 LAST MATERIAL X7R
J 0
(2100 1200);
DISPLAY 0.510638 (2100 1200);
PAINT SKYBLUE (2100 1200);
FORCEPROP 1 LAST VALUE 0.1UF
J 0
(2100 1350);
DISPLAY 0.510638 (2100 1350);
PAINT SKYBLUE (2100 1350);
FORCEPROP 1 LAST TOLERANCE 10%
J 0
(2100 1250);
DISPLAY 0.510638 (2100 1250);
PAINT SKYBLUE (2100 1250);
FORCEPROP 1 LAST VOLTAGE 25V
J 0
(2100 1300);
DISPLAY 0.510638 (2100 1300);
PAINT SKYBLUE (2100 1300);
FORCEPROP 1 LAST PACK_TYPE 0402
J 0
(2100 1150);
DISPLAY 0.510638 (2100 1150);
PAINT SKYBLUE (2100 1150);
FORCEPROP 1 LAST PART_NUMBER CH4104K1B00
J 0
(2100 1100);
DISPLAY 0.510638 (2100 1100);
PAINT WHITE (2100 1100);
FORCEPROP 1 LAST PATH I151
J 0
(2100 1450);
DISPLAY 0.978723 (2100 1450);
PAINT WHITE (2100 1450);
DISPLAY INVISIBLE (2100 1450);
FORCEPROP 2 LAST CDS_LIB pure_quanta
J 0
(2050 1300);
DISPLAY INVISIBLE (2050 1300);
FORCEPROP 1 LAST LOCATION C175
J 0
(2100 1400);
DISPLAY 0.702128 (2100 1400);
PAINT YELLOW (2100 1400);
FORCEPROP 1 LASTPIN (2050 1400) $PN 1
J 0
(2060 1380);
DISPLAY 0.808511 (2060 1380);
PAINT WHITE (2060 1380);
FORCEPROP 1 LASTPIN (2050 1200) $PN 2
J 0
(2060 1180);
DISPLAY 0.808511 (2060 1180);
PAINT WHITE (2060 1180);
FORCEPROP 0 LAST $SEC 1
J 0
(2100 1450);
DISPLAY 0.680851 (2100 1450);
PAINT MONO (2100 1450);
DISPLAY INVISIBLE (2100 1450);
FORCEPROP 0 LAST CDS_SEC 1
J 0
(2100 1450);
DISPLAY 0.680851 (2100 1450);
DISPLAY INVISIBLE (2100 1450);
FORCEADD UNIVERSAL_GND..1
(2050 1075);
FORCEPROP 3 LASTPIN (2050 1125) SIG_NAME GND\g
J 0
(2060 1135);
DISPLAY 0.659574 (2060 1135);
PAINT MONO (2060 1135);
DISPLAY INVISIBLE (2060 1135);
FORCEPROP 1 LAST PATH I152
J 0
(2125 1075);
DISPLAY 0.872340 (2125 1075);
PAINT AQUA (2125 1075);
DISPLAY INVISIBLE (2125 1075);
FORCEPROP 1 LAST HDL_POWER GND
J 1
(2075 1000);
DISPLAY 0.702128 (2075 1000);
PAINT GREEN (2075 1000);
DISPLAY INVISIBLE (2075 1000);
FORCEPROP 2 LAST CDS_LIB logical_power
J 0
(2050 1075);
DISPLAY INVISIBLE (2050 1075);
FORCEADD UNIVERSAL_GND..1
(975 600);
FORCEPROP 3 LASTPIN (975 650) SIG_NAME GND\g
J 0
(985 660);
DISPLAY 0.659574 (985 660);
PAINT MONO (985 660);
DISPLAY INVISIBLE (985 660);
FORCEPROP 1 LAST PATH I154
J 0
(1050 600);
DISPLAY 0.872340 (1050 600);
PAINT AQUA (1050 600);
DISPLAY INVISIBLE (1050 600);
FORCEPROP 1 LAST HDL_POWER GND
J 1
(1000 525);
DISPLAY 0.702128 (1000 525);
PAINT GREEN (1000 525);
DISPLAY INVISIBLE (1000 525);
FORCEPROP 2 LAST CDS_LIB logical_power
J 0
(975 600);
DISPLAY INVISIBLE (975 600);
FORCEADD OFFPAGE..4
R 2
(-50 950);
FORCEPROP 2 LAST $XR0 30 
J 0
(-271 950);
DISPLAY 0.638298 (-271 950);
PAINT MONO (-271 950);
FORCEPROP 2 LAST CDS_LIB standard
J 2
(-50 950);
DISPLAY 0.808511 (-50 950);
PAINT MONO (-50 950);
DISPLAY INVISIBLE (-50 950);
FORCEPROP 1 LAST OFFPAGE TRUE
J 2
(-375 825);
DISPLAY 0.872340 (-375 825);
PAINT GREEN (-375 825);
DISPLAY INVISIBLE (-375 825);
FORCEPROP 1 LAST COMMENT_BODY TRUE
J 2
(-25 850);
DISPLAY 0.872340 (-25 850);
PAINT PEACH (-25 850);
DISPLAY INVISIBLE (-25 850);
FORCEPROP 2 LAST PATH I172
J 0
(-300 1000);
DISPLAY 0.680851 (-300 1000);
DISPLAY INVISIBLE (-300 1000);
FORCEADD OFFPAGE..4
R 2
(-50 850);
FORCEPROP 2 LAST $XR0 30 
J 0
(-271 850);
DISPLAY 0.638298 (-271 850);
PAINT MONO (-271 850);
FORCEPROP 2 LAST CDS_LIB standard
J 2
(-50 850);
DISPLAY 0.808511 (-50 850);
PAINT MONO (-50 850);
DISPLAY INVISIBLE (-50 850);
FORCEPROP 1 LAST OFFPAGE TRUE
J 2
(-375 725);
DISPLAY 0.872340 (-375 725);
PAINT GREEN (-375 725);
DISPLAY INVISIBLE (-375 725);
FORCEPROP 1 LAST COMMENT_BODY TRUE
J 2
(-25 750);
DISPLAY 0.872340 (-25 750);
PAINT PEACH (-25 750);
DISPLAY INVISIBLE (-25 750);
FORCEPROP 2 LAST PATH I173
J 0
(-300 900);
DISPLAY 0.680851 (-300 900);
DISPLAY INVISIBLE (-300 900);
FORCEADD OFFPAGE..4
(-875 975);
FORCEPROP 2 LAST $XR0 30 
J 0
(-689 975);
DISPLAY 0.638298 (-689 975);
PAINT MONO (-689 975);
FORCEPROP 2 LAST PATH I175
J 0
(-675 1025);
DISPLAY 0.680851 (-675 1025);
DISPLAY INVISIBLE (-675 1025);
FORCEPROP 1 LAST COMMENT_BODY TRUE
J 0
(-900 875);
DISPLAY 0.872340 (-900 875);
PAINT PEACH (-900 875);
DISPLAY INVISIBLE (-900 875);
FORCEPROP 1 LAST OFFPAGE TRUE
J 0
(-550 850);
DISPLAY 0.872340 (-550 850);
PAINT GREEN (-550 850);
DISPLAY INVISIBLE (-550 850);
FORCEPROP 2 LAST CDS_LIB standard
J 0
(-875 975);
DISPLAY 0.808511 (-875 975);
PAINT MONO (-875 975);
DISPLAY INVISIBLE (-875 975);
FORCEADD OFFPAGE..2
(-875 875);
FORCEPROP 2 LAST $XR0 30 
J 0
(-686 875);
DISPLAY 0.638298 (-686 875);
PAINT MONO (-686 875);
FORCEPROP 2 LAST PATH I176
J 0
(-675 925);
DISPLAY 0.680851 (-675 925);
DISPLAY INVISIBLE (-675 925);
FORCEPROP 1 LAST COMMENT_BODY TRUE
J 0
(-920 780);
DISPLAY 0.872340 (-920 780);
PAINT PEACH (-920 780);
DISPLAY INVISIBLE (-920 780);
FORCEPROP 1 LAST OFFPAGE TRUE
J 0
(-550 750);
DISPLAY 0.872340 (-550 750);
PAINT GREEN (-550 750);
DISPLAY INVISIBLE (-550 750);
FORCEPROP 2 LAST CDS_LIB standard
J 0
(-875 875);
DISPLAY INVISIBLE (-875 875);
FORCEADD OFFPAGE..5
(-625 4175);
FORCEPROP 2 LAST $XR0 31 
J 0
(-849 4175);
DISPLAY 0.638298 (-849 4175);
PAINT MONO (-849 4175);
FORCEPROP 2 LAST CDS_LIB standard
J 0
(-625 4175);
PAINT MONO (-625 4175);
DISPLAY INVISIBLE (-625 4175);
FORCEPROP 1 LAST OFFPAGE TRUE
J 0
(-300 4050);
DISPLAY 0.872340 (-300 4050);
PAINT GREEN (-300 4050);
DISPLAY INVISIBLE (-300 4050);
FORCEPROP 1 LAST COMMENT_BODY TRUE
J 0
(-525 4100);
DISPLAY 0.872340 (-525 4100);
PAINT PEACH (-525 4100);
DISPLAY INVISIBLE (-525 4100);
FORCEPROP 2 LAST PATH I179
J 0
(-825 4225);
DISPLAY 0.680851 (-825 4225);
DISPLAY INVISIBLE (-825 4225);
FORCEADD OFFPAGE..1
(-625 3200);
FORCEPROP 2 LAST $XR0 31 
J 0
(-876 3200);
DISPLAY 0.638298 (-876 3200);
PAINT MONO (-876 3200);
FORCEPROP 2 LAST CDS_LIB standard
J 0
(-625 3200);
DISPLAY 0.808511 (-625 3200);
PAINT MONO (-625 3200);
DISPLAY INVISIBLE (-625 3200);
FORCEPROP 1 LAST OFFPAGE TRUE
J 0
(-295 3070);
PAINT GREEN (-295 3070);
DISPLAY INVISIBLE (-295 3070);
FORCEPROP 1 LAST COMMENT_BODY TRUE
J 0
(-495 3100);
DISPLAY 1.106383 (-495 3100);
PAINT PEACH (-495 3100);
DISPLAY INVISIBLE (-495 3100);
FORCEPROP 2 LAST PATH I181
J 0
(-875 3250);
DISPLAY 0.680851 (-875 3250);
DISPLAY INVISIBLE (-875 3250);
FORCEADD UNIVERSAL_GND..1
(-1850 600);
FORCEPROP 3 LASTPIN (-1850 650) SIG_NAME GND\g
J 0
(-1840 660);
DISPLAY 0.659574 (-1840 660);
PAINT MONO (-1840 660);
DISPLAY INVISIBLE (-1840 660);
FORCEPROP 1 LAST PATH I182
J 0
(-1775 600);
DISPLAY 0.872340 (-1775 600);
PAINT AQUA (-1775 600);
DISPLAY INVISIBLE (-1775 600);
FORCEPROP 1 LAST HDL_POWER GND
J 1
(-1825 525);
DISPLAY 0.702128 (-1825 525);
PAINT GREEN (-1825 525);
DISPLAY INVISIBLE (-1825 525);
FORCEPROP 2 LAST CDS_LIB logical_power
J 0
(-1850 600);
DISPLAY INVISIBLE (-1850 600);
FORCEADD SCONN3_21291035BR2..1
R 2
(-2225 925);
FORCEPROP 1 LAST PART_NUMBER DFHD03MS251
J 2
(-2175 1125);
DISPLAY 0.723404 (-2175 1125);
PAINT GREEN (-2175 1125);
FORCEPROP 2 LAST VALUE SCONN3_212-91-035BR2
J 2
(-2175 1250);
DISPLAY 0.680851 (-2175 1250);
FORCEPROP 2 LAST PART_TYPE SMLF
J 2
(-2175 1300);
DISPLAY 0.680851 (-2175 1300);
FORCEPROP 1 LAST MATERIAL EMPTY
J 2
(-2175 1050);
DISPLAY 0.723404 (-2175 1050);
PAINT RED (-2175 1050);
FORCEPROP 1 LAST PATH I184
J 2
(-2225 925);
DISPLAY 0.723404 (-2225 925);
PAINT GREEN (-2225 925);
DISPLAY INVISIBLE (-2225 925);
FORCEPROP 1 LAST CDS_LMAN_SYM_OUTLINE -50,100,50,-100
J 2
(-2225 925);
DISPLAY 0.468085 (-2225 925);
PAINT GREEN (-2225 925);
DISPLAY INVISIBLE (-2225 925);
FORCEPROP 1 LAST NEEDS_NO_SIZE TRUE
J 2
(-2225 925);
DISPLAY 0.723404 (-2225 925);
PAINT GREEN (-2225 925);
DISPLAY INVISIBLE (-2225 925);
FORCEPROP 2 LAST CDS_LIB pure_quanta
J 2
(-2225 925);
DISPLAY INVISIBLE (-2225 925);
FORCEPROP 2 LAST SEC_TYPE 
J 0
(-2175 1350);
DISPLAY 0.680851 (-2175 1350);
DISPLAY INVISIBLE (-2175 1350);
FORCEPROP 1 LAST LOCATION J6
J 2
(-2175 1200);
DISPLAY 0.723404 (-2175 1200);
PAINT GREEN (-2175 1200);
FORCEPROP 0 LASTPIN (-2025 975) $PN 1
J 0
(-2015 985);
DISPLAY 0.680851 (-2015 985);
PAINT MONO (-2015 985);
FORCEPROP 0 LASTPIN (-2025 925) $PN 2
J 0
(-2015 935);
DISPLAY 0.680851 (-2015 935);
PAINT MONO (-2015 935);
FORCEPROP 0 LASTPIN (-2025 875) $PN 3
J 0
(-2015 885);
DISPLAY 0.680851 (-2015 885);
PAINT MONO (-2015 885);
FORCEPROP 2 LAST SEC 1
J 0
(-2175 1350);
DISPLAY 0.680851 (-2175 1350);
PAINT MONO (-2175 1350);
DISPLAY INVISIBLE (-2175 1350);
FORCEADD Q_RES..2
R 2
(1525 3700);
FORCEPROP 1 LAST PACK_TYPE 0402LF
J 2
(1485 3525);
DISPLAY 0.510638 (1485 3525);
PAINT SKYBLUE (1485 3525);
FORCEPROP 1 LAST MATERIAL EMPTY
J 2
(1485 3625);
DISPLAY 0.510638 (1485 3625);
PAINT RED (1485 3625);
FORCEPROP 1 LAST WATTAGE 1/16W
J 2
(1485 3675);
DISPLAY 0.510638 (1485 3675);
PAINT SKYBLUE (1485 3675);
FORCEPROP 1 LAST PART_NUMBER CS24702FB06
J 2
(1485 3575);
DISPLAY 0.510638 (1485 3575);
PAINT WHITE (1485 3575);
FORCEPROP 1 LAST VALUE 4.7K
J 2
(1480 3775);
DISPLAY 0.510638 (1480 3775);
PAINT SKYBLUE (1480 3775);
FORCEPROP 1 LAST TOLERANCE 1%
J 2
(1480 3725);
DISPLAY 0.510638 (1480 3725);
PAINT SKYBLUE (1480 3725);
FORCEPROP 1 LAST PATH I192
J 2
(1475 3875);
DISPLAY 0.978723 (1475 3875);
PAINT WHITE (1475 3875);
DISPLAY INVISIBLE (1475 3875);
FORCEPROP 2 LAST SEC_TYPE 0402LF
J 0
(1475 3925);
DISPLAY 0.680851 (1475 3925);
DISPLAY INVISIBLE (1475 3925);
FORCEPROP 2 LAST CDS_LIB pure_quanta
J 2
(1525 3700);
PAINT MONO (1525 3700);
DISPLAY INVISIBLE (1525 3700);
FORCEPROP 1 LAST LOCATION R737
J 2
(1480 3825);
DISPLAY 0.702128 (1480 3825);
PAINT YELLOW (1480 3825);
FORCEPROP 1 LASTPIN (1525 3800) $PN 1
J 2
(1520 3762);
DISPLAY 0.808511 (1520 3762);
PAINT WHITE (1520 3762);
FORCEPROP 1 LASTPIN (1525 3600) $PN 2
J 2
(1520 3610);
DISPLAY 0.808511 (1520 3610);
PAINT WHITE (1520 3610);
FORCEPROP 2 LAST SEC 1
J 0
(1475 3925);
DISPLAY 0.680851 (1475 3925);
PAINT MONO (1475 3925);
DISPLAY INVISIBLE (1475 3925);
FORCEADD Q_RES..2
R 2
(1675 4725);
FORCEPROP 1 LAST MATERIAL EMPTY
J 2
(1635 4650);
DISPLAY 0.510638 (1635 4650);
PAINT RED (1635 4650);
FORCEPROP 1 LAST PACK_TYPE 0402LF
J 2
(1635 4550);
DISPLAY 0.510638 (1635 4550);
PAINT SKYBLUE (1635 4550);
FORCEPROP 1 LAST PART_NUMBER CS24702FB06
J 2
(1635 4600);
DISPLAY 0.510638 (1635 4600);
PAINT WHITE (1635 4600);
FORCEPROP 1 LAST VALUE 4.7K
J 2
(1630 4800);
DISPLAY 0.510638 (1630 4800);
PAINT SKYBLUE (1630 4800);
FORCEPROP 1 LAST TOLERANCE 1%
J 2
(1630 4750);
DISPLAY 0.510638 (1630 4750);
PAINT SKYBLUE (1630 4750);
FORCEPROP 1 LAST WATTAGE 1/16W
J 2
(1635 4700);
DISPLAY 0.510638 (1635 4700);
PAINT SKYBLUE (1635 4700);
FORCEPROP 1 LAST PATH I195
J 2
(1625 4900);
DISPLAY 0.978723 (1625 4900);
PAINT WHITE (1625 4900);
DISPLAY INVISIBLE (1625 4900);
FORCEPROP 2 LAST SEC_TYPE 0402LF
J 0
(1625 4950);
DISPLAY 0.680851 (1625 4950);
DISPLAY INVISIBLE (1625 4950);
FORCEPROP 2 LAST CDS_LIB pure_quanta
J 2
(1675 4725);
PAINT MONO (1675 4725);
DISPLAY INVISIBLE (1675 4725);
FORCEPROP 1 LAST LOCATION R742
J 2
(1630 4850);
DISPLAY 0.702128 (1630 4850);
PAINT YELLOW (1630 4850);
FORCEPROP 1 LASTPIN (1675 4825) $PN 1
J 2
(1670 4787);
DISPLAY 0.808511 (1670 4787);
PAINT WHITE (1670 4787);
FORCEPROP 1 LASTPIN (1675 4625) $PN 2
J 2
(1670 4635);
DISPLAY 0.808511 (1670 4635);
PAINT WHITE (1670 4635);
FORCEPROP 2 LAST SEC 1
J 0
(1625 4950);
DISPLAY 0.680851 (1625 4950);
PAINT MONO (1625 4950);
DISPLAY INVISIBLE (1625 4950);
FORCEADD Q_RES..2
R 2
(850 1275);
FORCEPROP 1 LAST MATERIAL CHIP
J 2
(810 1200);
DISPLAY 0.510638 (810 1200);
PAINT SKYBLUE (810 1200);
FORCEPROP 1 LAST WATTAGE 1/16W
J 2
(810 1250);
DISPLAY 0.510638 (810 1250);
PAINT SKYBLUE (810 1250);
FORCEPROP 1 LAST TOLERANCE 1%
J 2
(805 1300);
DISPLAY 0.510638 (805 1300);
PAINT SKYBLUE (805 1300);
FORCEPROP 1 LAST PACK_TYPE 0402LF
J 2
(810 1100);
DISPLAY 0.510638 (810 1100);
PAINT SKYBLUE (810 1100);
FORCEPROP 1 LAST PART_NUMBER CS24702FB06
J 2
(810 1150);
DISPLAY 0.510638 (810 1150);
PAINT WHITE (810 1150);
FORCEPROP 1 LAST VALUE 4.7K
J 2
(805 1350);
DISPLAY 0.510638 (805 1350);
PAINT SKYBLUE (805 1350);
FORCEPROP 1 LAST PATH I197
J 2
(800 1450);
DISPLAY 0.978723 (800 1450);
PAINT WHITE (800 1450);
DISPLAY INVISIBLE (800 1450);
FORCEPROP 2 LAST CDS_LIB pure_quanta
J 2
(850 1275);
PAINT MONO (850 1275);
DISPLAY INVISIBLE (850 1275);
FORCEPROP 2 LAST SEC_TYPE 0402LF
J 0
(800 1500);
DISPLAY 0.680851 (800 1500);
DISPLAY INVISIBLE (800 1500);
FORCEPROP 1 LAST LOCATION R741
J 2
(805 1400);
DISPLAY 0.702128 (805 1400);
PAINT YELLOW (805 1400);
FORCEPROP 1 LASTPIN (850 1375) $PN 1
J 2
(845 1337);
DISPLAY 0.808511 (845 1337);
PAINT WHITE (845 1337);
FORCEPROP 1 LASTPIN (850 1175) $PN 2
J 2
(845 1185);
DISPLAY 0.808511 (845 1185);
PAINT WHITE (845 1185);
FORCEPROP 2 LAST SEC 1
J 0
(800 1500);
DISPLAY 0.680851 (800 1500);
PAINT MONO (800 1500);
DISPLAY INVISIBLE (800 1500);
FORCEADD UNIVERSAL_POWER..1
(1825 2725);
FORCEPROP 3 LASTPIN (1825 2675) SIG_NAME P3V3_AUX\g
J 0
(1835 2685);
DISPLAY 0.659574 (1835 2685);
PAINT MONO (1835 2685);
DISPLAY INVISIBLE (1835 2685);
FORCEPROP 1 LAST HDL_POWER P3V3_AUX
J 1
(1825 2775);
DISPLAY 0.702128 (1825 2775);
PAINT PEACH (1825 2775);
FORCEPROP 1 LAST PATH I207
J 0
(1875 2750);
DISPLAY 0.872340 (1875 2750);
PAINT AQUA (1875 2750);
DISPLAY INVISIBLE (1875 2750);
FORCEPROP 2 LAST CDS_LIB logical_power
J 0
(1825 2725);
DISPLAY INVISIBLE (1825 2725);
FORCEADD UNIVERSAL_POWER..1
(850 1525);
FORCEPROP 3 LASTPIN (850 1475) SIG_NAME P3V3_AUX\g
J 0
(860 1485);
DISPLAY 0.659574 (860 1485);
PAINT MONO (860 1485);
DISPLAY INVISIBLE (860 1485);
FORCEPROP 1 LAST HDL_POWER P3V3_AUX
J 1
(850 1575);
DISPLAY 0.702128 (850 1575);
PAINT PEACH (850 1575);
FORCEPROP 1 LAST PATH I208
J 0
(900 1550);
DISPLAY 0.872340 (900 1550);
PAINT AQUA (900 1550);
DISPLAY INVISIBLE (900 1550);
FORCEPROP 2 LAST CDS_LIB logical_power
J 0
(850 1525);
DISPLAY INVISIBLE (850 1525);
FORCEADD UNIVERSAL_POWER..1
(1850 1575);
FORCEPROP 3 LASTPIN (1850 1525) SIG_NAME P3V3_AUX\g
J 0
(1860 1535);
DISPLAY 0.659574 (1860 1535);
PAINT MONO (1860 1535);
DISPLAY INVISIBLE (1860 1535);
FORCEPROP 1 LAST HDL_POWER P3V3_AUX
J 1
(1850 1625);
DISPLAY 0.702128 (1850 1625);
PAINT PEACH (1850 1625);
FORCEPROP 1 LAST PATH I211
J 0
(1900 1600);
DISPLAY 0.872340 (1900 1600);
PAINT AQUA (1900 1600);
DISPLAY INVISIBLE (1900 1600);
FORCEPROP 2 LAST CDS_LIB logical_power
J 0
(1850 1575);
DISPLAY INVISIBLE (1850 1575);
FORCEADD UNIVERSAL_POWER..1
(1525 4000);
FORCEPROP 3 LASTPIN (1525 3950) SIG_NAME P3V3_AUX\g
J 0
(1535 3960);
DISPLAY 0.659574 (1535 3960);
PAINT MONO (1535 3960);
DISPLAY INVISIBLE (1535 3960);
FORCEPROP 1 LAST HDL_POWER P3V3_AUX
J 1
(1525 4050);
DISPLAY 0.702128 (1525 4050);
PAINT PEACH (1525 4050);
FORCEPROP 1 LAST PATH I214
J 0
(1575 4025);
DISPLAY 0.872340 (1575 4025);
PAINT AQUA (1575 4025);
DISPLAY INVISIBLE (1575 4025);
FORCEPROP 2 LAST CDS_LIB logical_power
J 0
(1525 4000);
DISPLAY INVISIBLE (1525 4000);
FORCEADD UNIVERSAL_POWER..1
(1675 4925);
FORCEPROP 3 LASTPIN (1675 4875) SIG_NAME P3V3_AUX\g
J 0
(1685 4885);
DISPLAY 0.659574 (1685 4885);
PAINT MONO (1685 4885);
DISPLAY INVISIBLE (1685 4885);
FORCEPROP 1 LAST HDL_POWER P3V3_AUX
J 1
(1675 4975);
DISPLAY 0.702128 (1675 4975);
PAINT PEACH (1675 4975);
FORCEPROP 1 LAST PATH I217
J 0
(1725 4950);
DISPLAY 0.872340 (1725 4950);
PAINT AQUA (1725 4950);
DISPLAY INVISIBLE (1725 4950);
FORCEPROP 2 LAST CDS_LIB logical_power
J 0
(1675 4925);
DISPLAY INVISIBLE (1675 4925);
FORCEADD OFFPAGE..2
(3275 2150);
FORCEPROP 2 LAST $XR0 30 
J 0
(3464 2150);
DISPLAY 0.638298 (3464 2150);
PAINT MONO (3464 2150);
FORCEPROP 2 LAST PATH I219
J 0
(3475 2200);
DISPLAY 0.680851 (3475 2200);
DISPLAY INVISIBLE (3475 2200);
FORCEPROP 1 LAST COMMENT_BODY TRUE
J 0
(3230 2055);
DISPLAY 0.872340 (3230 2055);
PAINT PEACH (3230 2055);
DISPLAY INVISIBLE (3230 2055);
FORCEPROP 1 LAST OFFPAGE TRUE
J 0
(3600 2025);
DISPLAY 0.872340 (3600 2025);
PAINT GREEN (3600 2025);
DISPLAY INVISIBLE (3600 2025);
FORCEPROP 2 LAST CDS_LIB standard
J 0
(3275 2150);
DISPLAY 0.808511 (3275 2150);
PAINT MONO (3275 2150);
DISPLAY INVISIBLE (3275 2150);
FORCEADD OFFPAGE..2
(3275 2050);
FORCEPROP 2 LAST $XR0 13 
J 0
(3464 2050);
DISPLAY 0.638298 (3464 2050);
PAINT MONO (3464 2050);
FORCEPROP 2 LAST PATH I220
J 0
(3575 2100);
DISPLAY 0.680851 (3575 2100);
DISPLAY INVISIBLE (3575 2100);
FORCEPROP 1 LAST COMMENT_BODY TRUE
J 0
(3230 1955);
DISPLAY 0.872340 (3230 1955);
PAINT PEACH (3230 1955);
DISPLAY INVISIBLE (3230 1955);
FORCEPROP 1 LAST OFFPAGE TRUE
J 0
(3600 1925);
DISPLAY 0.872340 (3600 1925);
PAINT GREEN (3600 1925);
DISPLAY INVISIBLE (3600 1925);
FORCEPROP 2 LAST CDS_LIB standard
J 0
(3275 2050);
DISPLAY 0.808511 (3275 2050);
PAINT MONO (3275 2050);
DISPLAY INVISIBLE (3275 2050);
FORCEADD Q_RES..2
R 2
(2200 2375);
FORCEPROP 1 LAST PACK_TYPE 0402LF
J 2
(2160 2200);
DISPLAY 0.510638 (2160 2200);
PAINT SKYBLUE (2160 2200);
FORCEPROP 1 LAST VALUE 4.7K
J 2
(2155 2450);
DISPLAY 0.510638 (2155 2450);
PAINT SKYBLUE (2155 2450);
FORCEPROP 1 LAST MATERIAL CHIP
J 2
(2160 2300);
DISPLAY 0.510638 (2160 2300);
PAINT SKYBLUE (2160 2300);
FORCEPROP 1 LAST PART_NUMBER CS24702FB06
J 2
(2160 2250);
DISPLAY 0.510638 (2160 2250);
PAINT WHITE (2160 2250);
FORCEPROP 1 LAST WATTAGE 1/16W
J 2
(2160 2350);
DISPLAY 0.510638 (2160 2350);
PAINT SKYBLUE (2160 2350);
FORCEPROP 1 LAST TOLERANCE 1%
J 2
(2155 2400);
DISPLAY 0.510638 (2155 2400);
PAINT SKYBLUE (2155 2400);
FORCEPROP 1 LAST PATH I221
J 2
(2150 2550);
DISPLAY 0.978723 (2150 2550);
PAINT WHITE (2150 2550);
DISPLAY INVISIBLE (2150 2550);
FORCEPROP 2 LAST SEC_TYPE 0402LF
J 0
(2150 2600);
DISPLAY 0.680851 (2150 2600);
DISPLAY INVISIBLE (2150 2600);
FORCEPROP 2 LAST CDS_LIB pure_quanta
J 2
(2200 2375);
PAINT MONO (2200 2375);
DISPLAY INVISIBLE (2200 2375);
FORCEPROP 1 LAST LOCATION R758
J 2
(2155 2500);
DISPLAY 0.702128 (2155 2500);
PAINT YELLOW (2155 2500);
FORCEPROP 1 LASTPIN (2200 2475) $PN 1
J 2
(2195 2437);
DISPLAY 0.808511 (2195 2437);
PAINT WHITE (2195 2437);
FORCEPROP 1 LASTPIN (2200 2275) $PN 2
J 2
(2195 2285);
DISPLAY 0.808511 (2195 2285);
PAINT WHITE (2195 2285);
FORCEPROP 2 LAST SEC 1
J 0
(2150 2600);
DISPLAY 0.680851 (2150 2600);
PAINT MONO (2150 2600);
DISPLAY INVISIBLE (2150 2600);
FORCEADD Q_RES..1
(1275 2150);
FORCEPROP 1 LAST PACK_TYPE 0402LF
J 0
(1325 2100);
DISPLAY 0.510638 (1325 2100);
PAINT SKYBLUE (1325 2100);
FORCEPROP 1 LAST TOLERANCE 1%
J 0
(1500 2100);
DISPLAY 0.510638 (1500 2100);
PAINT SKYBLUE (1500 2100);
FORCEPROP 1 LAST WATTAGE 1/16W
J 2
(1675 2100);
DISPLAY 0.510638 (1675 2100);
PAINT SKYBLUE (1675 2100);
FORCEPROP 1 LAST MATERIAL CHIP
J 0
(1525 2150);
DISPLAY 0.510638 (1525 2150);
PAINT SKYBLUE (1525 2150);
FORCEPROP 1 LAST VALUE 33.2
J 0
(1400 2150);
DISPLAY 0.510638 (1400 2150);
PAINT SKYBLUE (1400 2150);
FORCEPROP 1 LAST PART_NUMBER CS03322FB03
J 0
(1400 2200);
DISPLAY 0.510638 (1400 2200);
PAINT WHITE (1400 2200);
DISPLAY INVISIBLE (1400 2200);
FORCEPROP 1 LAST PATH I225
J 0
(1225 2300);
DISPLAY 0.978723 (1225 2300);
PAINT WHITE (1225 2300);
DISPLAY INVISIBLE (1225 2300);
FORCEPROP 2 LAST SEC_TYPE 0402LF
J 0
(1225 2350);
DISPLAY 0.680851 (1225 2350);
DISPLAY INVISIBLE (1225 2350);
FORCEPROP 2 LAST CDS_LIB pure_quanta
J 0
(1275 2150);
DISPLAY INVISIBLE (1275 2150);
FORCEPROP 1 LAST LOCATION R715
J 0
(1050 2175);
DISPLAY 0.702128 (1050 2175);
PAINT YELLOW (1050 2175);
FORCEPROP 1 LASTPIN (1175 2150) $PN 1
J 0
(1187 2162);
DISPLAY 0.808511 (1187 2162);
PAINT WHITE (1187 2162);
FORCEPROP 1 LASTPIN (1375 2150) $PN 2
J 0
(1340 2160);
DISPLAY 0.808511 (1340 2160);
PAINT WHITE (1340 2160);
FORCEPROP 2 LAST SEC 1
J 0
(1225 2350);
DISPLAY 0.680851 (1225 2350);
PAINT MONO (1225 2350);
DISPLAY INVISIBLE (1225 2350);
FORCEADD Q_RES..1
(1275 2050);
FORCEPROP 1 LAST MATERIAL CHIP
J 0
(1525 2050);
DISPLAY 0.510638 (1525 2050);
PAINT SKYBLUE (1525 2050);
FORCEPROP 1 LAST VALUE 33.2
J 0
(1400 2050);
DISPLAY 0.510638 (1400 2050);
PAINT SKYBLUE (1400 2050);
FORCEPROP 1 LAST PACK_TYPE 0402LF
J 0
(1325 2000);
DISPLAY 0.510638 (1325 2000);
PAINT SKYBLUE (1325 2000);
FORCEPROP 1 LAST TOLERANCE 1%
J 0
(1500 2000);
DISPLAY 0.510638 (1500 2000);
PAINT SKYBLUE (1500 2000);
FORCEPROP 1 LAST WATTAGE 1/16W
J 2
(1675 2000);
DISPLAY 0.510638 (1675 2000);
PAINT SKYBLUE (1675 2000);
FORCEPROP 1 LAST PART_NUMBER CS03322FB03
J 0
(1400 2100);
DISPLAY 0.510638 (1400 2100);
PAINT WHITE (1400 2100);
DISPLAY INVISIBLE (1400 2100);
FORCEPROP 1 LAST PATH I226
J 0
(1225 2200);
DISPLAY 0.978723 (1225 2200);
PAINT WHITE (1225 2200);
DISPLAY INVISIBLE (1225 2200);
FORCEPROP 2 LAST SEC_TYPE 0402LF
J 0
(1225 2250);
DISPLAY 0.680851 (1225 2250);
DISPLAY INVISIBLE (1225 2250);
FORCEPROP 2 LAST CDS_LIB pure_quanta
J 0
(1275 2050);
DISPLAY INVISIBLE (1275 2050);
FORCEPROP 1 LAST LOCATION R757
J 0
(1050 2050);
DISPLAY 0.702128 (1050 2050);
PAINT YELLOW (1050 2050);
FORCEPROP 1 LASTPIN (1175 2050) $PN 1
J 0
(1187 2062);
DISPLAY 0.808511 (1187 2062);
PAINT WHITE (1187 2062);
FORCEPROP 1 LASTPIN (1375 2050) $PN 2
J 0
(1340 2060);
DISPLAY 0.808511 (1340 2060);
PAINT WHITE (1340 2060);
FORCEPROP 2 LAST SEC 1
J 0
(1225 2250);
DISPLAY 0.680851 (1225 2250);
PAINT MONO (1225 2250);
DISPLAY INVISIBLE (1225 2250);
FORCEADD UNIVERSAL_POWER..1
(175 2775);
FORCEPROP 3 LASTPIN (175 2725) SIG_NAME P3V3_AUX\g
J 0
(185 2735);
DISPLAY 0.659574 (185 2735);
PAINT MONO (185 2735);
DISPLAY INVISIBLE (185 2735);
FORCEPROP 1 LAST HDL_POWER P3V3_AUX
J 1
(175 2825);
DISPLAY 0.702128 (175 2825);
PAINT PEACH (175 2825);
FORCEPROP 1 LAST PATH I227
J 0
(225 2800);
DISPLAY 0.872340 (225 2800);
PAINT AQUA (225 2800);
DISPLAY INVISIBLE (225 2800);
FORCEPROP 2 LAST CDS_LIB logical_power
J 0
(175 2775);
DISPLAY INVISIBLE (175 2775);
FORCEADD UNIVERSAL_GND..1
(375 2275);
FORCEPROP 3 LASTPIN (375 2325) SIG_NAME GND\g
J 0
(385 2335);
DISPLAY 0.659574 (385 2335);
PAINT MONO (385 2335);
DISPLAY INVISIBLE (385 2335);
FORCEPROP 1 LAST PATH I228
J 0
(450 2275);
DISPLAY 0.872340 (450 2275);
PAINT AQUA (450 2275);
DISPLAY INVISIBLE (450 2275);
FORCEPROP 1 LAST HDL_POWER GND
J 1
(400 2200);
DISPLAY 0.702128 (400 2200);
PAINT GREEN (400 2200);
DISPLAY INVISIBLE (400 2200);
FORCEPROP 2 LAST CDS_LIB logical_power
J 0
(375 2275);
DISPLAY INVISIBLE (375 2275);
FORCEADD Q_CAP..1
(375 2500);
FORCEPROP 1 LAST TOLERANCE 10%
J 0
(425 2450);
DISPLAY 0.510638 (425 2450);
PAINT SKYBLUE (425 2450);
FORCEPROP 1 LAST PART_NUMBER CH4104K1B00
J 0
(425 2300);
DISPLAY 0.510638 (425 2300);
PAINT WHITE (425 2300);
FORCEPROP 1 LAST VALUE 0.1UF
J 0
(425 2550);
DISPLAY 0.510638 (425 2550);
PAINT SKYBLUE (425 2550);
FORCEPROP 1 LAST VOLTAGE 25V
J 0
(425 2500);
DISPLAY 0.510638 (425 2500);
PAINT SKYBLUE (425 2500);
FORCEPROP 1 LAST MATERIAL X7R
J 0
(425 2400);
DISPLAY 0.510638 (425 2400);
PAINT SKYBLUE (425 2400);
FORCEPROP 1 LAST PACK_TYPE 0402
J 0
(425 2350);
DISPLAY 0.510638 (425 2350);
PAINT SKYBLUE (425 2350);
FORCEPROP 1 LAST PATH I229
J 0
(425 2650);
DISPLAY 0.978723 (425 2650);
PAINT WHITE (425 2650);
DISPLAY INVISIBLE (425 2650);
FORCEPROP 2 LAST CDS_LIB pure_quanta
J 0
(375 2500);
DISPLAY INVISIBLE (375 2500);
FORCEPROP 1 LAST LOCATION C268
J 0
(425 2600);
DISPLAY 0.702128 (425 2600);
PAINT YELLOW (425 2600);
FORCEPROP 1 LASTPIN (375 2600) $PN 1
J 0
(385 2580);
DISPLAY 0.808511 (385 2580);
PAINT WHITE (385 2580);
FORCEPROP 1 LASTPIN (375 2400) $PN 2
J 0
(385 2380);
DISPLAY 0.808511 (385 2380);
PAINT WHITE (385 2380);
FORCEPROP 0 LAST $SEC 1
J 0
(425 2650);
DISPLAY 0.680851 (425 2650);
PAINT MONO (425 2650);
DISPLAY INVISIBLE (425 2650);
FORCEPROP 0 LAST CDS_SEC 1
J 0
(425 2650);
DISPLAY 0.680851 (425 2650);
DISPLAY INVISIBLE (425 2650);
FORCEADD UNIVERSAL_POWER..1
(-825 2725);
FORCEPROP 3 LASTPIN (-825 2675) SIG_NAME P3V3_AUX\g
J 0
(-815 2685);
DISPLAY 0.659574 (-815 2685);
PAINT MONO (-815 2685);
DISPLAY INVISIBLE (-815 2685);
FORCEPROP 1 LAST HDL_POWER P3V3_AUX
J 1
(-825 2775);
DISPLAY 0.702128 (-825 2775);
PAINT PEACH (-825 2775);
FORCEPROP 1 LAST PATH I230
J 0
(-775 2750);
DISPLAY 0.872340 (-775 2750);
PAINT AQUA (-775 2750);
DISPLAY INVISIBLE (-775 2750);
FORCEPROP 2 LAST CDS_LIB logical_power
J 0
(-825 2725);
DISPLAY INVISIBLE (-825 2725);
FORCEADD Q_RES..2
R 2
(-825 2475);
FORCEPROP 1 LAST PACK_TYPE 0402LF
J 2
(-865 2300);
DISPLAY 0.510638 (-865 2300);
PAINT SKYBLUE (-865 2300);
FORCEPROP 1 LAST VALUE 4.7K
J 2
(-870 2550);
DISPLAY 0.510638 (-870 2550);
PAINT SKYBLUE (-870 2550);
FORCEPROP 1 LAST WATTAGE 1/16W
J 2
(-865 2450);
DISPLAY 0.510638 (-865 2450);
PAINT SKYBLUE (-865 2450);
FORCEPROP 1 LAST TOLERANCE 1%
J 2
(-870 2500);
DISPLAY 0.510638 (-870 2500);
PAINT SKYBLUE (-870 2500);
FORCEPROP 1 LAST PART_NUMBER CS24702FB06
J 2
(-865 2350);
DISPLAY 0.510638 (-865 2350);
PAINT WHITE (-865 2350);
FORCEPROP 1 LAST MATERIAL CHIP
J 2
(-865 2400);
DISPLAY 0.510638 (-865 2400);
PAINT SKYBLUE (-865 2400);
FORCEPROP 1 LAST PATH I231
J 2
(-875 2650);
DISPLAY 0.978723 (-875 2650);
PAINT WHITE (-875 2650);
DISPLAY INVISIBLE (-875 2650);
FORCEPROP 2 LAST SEC_TYPE 0402LF
J 0
(-875 2700);
DISPLAY 0.680851 (-875 2700);
DISPLAY INVISIBLE (-875 2700);
FORCEPROP 2 LAST CDS_LIB pure_quanta
J 2
(-825 2475);
PAINT MONO (-825 2475);
DISPLAY INVISIBLE (-825 2475);
FORCEPROP 1 LAST LOCATION R72
J 2
(-870 2600);
DISPLAY 0.702128 (-870 2600);
PAINT YELLOW (-870 2600);
FORCEPROP 1 LASTPIN (-825 2575) $PN 1
J 2
(-830 2537);
DISPLAY 0.808511 (-830 2537);
PAINT WHITE (-830 2537);
FORCEPROP 1 LASTPIN (-825 2375) $PN 2
J 2
(-830 2385);
DISPLAY 0.808511 (-830 2385);
PAINT WHITE (-830 2385);
FORCEPROP 2 LAST SEC 1
J 0
(-875 2700);
DISPLAY 0.680851 (-875 2700);
PAINT MONO (-875 2700);
DISPLAY INVISIBLE (-875 2700);
FORCEADD UNIVERSAL_GND..1
(-700 1800);
FORCEPROP 3 LASTPIN (-700 1850) SIG_NAME GND\g
J 0
(-690 1860);
DISPLAY 0.659574 (-690 1860);
PAINT MONO (-690 1860);
DISPLAY INVISIBLE (-690 1860);
FORCEPROP 1 LAST PATH I233
J 0
(-625 1800);
DISPLAY 0.872340 (-625 1800);
PAINT AQUA (-625 1800);
DISPLAY INVISIBLE (-625 1800);
FORCEPROP 1 LAST HDL_POWER GND
J 1
(-675 1725);
DISPLAY 0.702128 (-675 1725);
PAINT GREEN (-675 1725);
DISPLAY INVISIBLE (-675 1725);
FORCEPROP 2 LAST CDS_LIB logical_power
J 0
(-700 1800);
DISPLAY INVISIBLE (-700 1800);
FORCEADD OFFPAGE..4
R 2
(-1675 2150);
FORCEPROP 2 LAST $XR0 13 
J 0
(-1926 2150);
DISPLAY 0.638298 (-1926 2150);
PAINT MONO (-1926 2150);
FORCEPROP 2 LAST $XR1 27 
J 0
(-2016 2150);
DISPLAY 0.638298 (-2016 2150);
PAINT MONO (-2016 2150);
FORCEPROP 2 LAST PATH I234
J 0
(-1875 2200);
DISPLAY 0.680851 (-1875 2200);
DISPLAY INVISIBLE (-1875 2200);
FORCEPROP 1 LAST COMMENT_BODY TRUE
J 2
(-1650 2050);
DISPLAY 0.872340 (-1650 2050);
PAINT PEACH (-1650 2050);
DISPLAY INVISIBLE (-1650 2050);
FORCEPROP 1 LAST OFFPAGE TRUE
J 2
(-2000 2025);
DISPLAY 0.872340 (-2000 2025);
PAINT GREEN (-2000 2025);
DISPLAY INVISIBLE (-2000 2025);
FORCEPROP 2 LAST CDS_LIB standard
J 2
(-1675 2150);
DISPLAY 0.808511 (-1675 2150);
PAINT MONO (-1675 2150);
DISPLAY INVISIBLE (-1675 2150);
FORCEADD OFFPAGE..4
R 2
(-1675 2050);
FORCEPROP 2 LAST $XR0 30 
J 0
(-1926 2050);
DISPLAY 0.638298 (-1926 2050);
PAINT MONO (-1926 2050);
FORCEPROP 2 LAST PATH I235
J 0
(-1875 2100);
DISPLAY 0.680851 (-1875 2100);
DISPLAY INVISIBLE (-1875 2100);
FORCEPROP 1 LAST COMMENT_BODY TRUE
J 2
(-1650 1950);
DISPLAY 0.872340 (-1650 1950);
PAINT PEACH (-1650 1950);
DISPLAY INVISIBLE (-1650 1950);
FORCEPROP 1 LAST OFFPAGE TRUE
J 2
(-2000 1925);
DISPLAY 0.872340 (-2000 1925);
PAINT GREEN (-2000 1925);
DISPLAY INVISIBLE (-2000 1925);
FORCEPROP 2 LAST CDS_LIB standard
J 2
(-1675 2050);
DISPLAY 0.808511 (-1675 2050);
PAINT MONO (-1675 2050);
DISPLAY INVISIBLE (-1675 2050);
FORCEADD UNIVERSAL_POWER..1
(2200 2650);
FORCEPROP 3 LASTPIN (2200 2600) SIG_NAME P3V3_RGM\g
J 0
(2210 2610);
DISPLAY 0.659574 (2210 2610);
PAINT MONO (2210 2610);
DISPLAY INVISIBLE (2210 2610);
FORCEPROP 1 LAST HDL_POWER P3V3_RGM
J 1
(2200 2700);
DISPLAY 0.702128 (2200 2700);
PAINT GREEN (2200 2700);
FORCEPROP 1 LAST PATH I236
J 0
(2250 2675);
DISPLAY 0.872340 (2250 2675);
PAINT AQUA (2250 2675);
DISPLAY INVISIBLE (2250 2675);
FORCEPROP 2 LAST CDS_LIB logical_power
J 0
(2200 2650);
DISPLAY INVISIBLE (2200 2650);
FORCEADD Q_RES..1
(4900 2675);
FORCEPROP 1 LAST VALUE 33.2
J 0
(5025 2675);
DISPLAY 0.510638 (5025 2675);
PAINT SKYBLUE (5025 2675);
FORCEPROP 1 LAST MATERIAL CHIP
J 0
(5150 2675);
DISPLAY 0.510638 (5150 2675);
PAINT SKYBLUE (5150 2675);
FORCEPROP 1 LAST WATTAGE 1/16W
J 2
(5300 2625);
DISPLAY 0.510638 (5300 2625);
PAINT SKYBLUE (5300 2625);
FORCEPROP 1 LAST PACK_TYPE 0402LF
J 0
(4950 2625);
DISPLAY 0.510638 (4950 2625);
PAINT SKYBLUE (4950 2625);
FORCEPROP 1 LAST TOLERANCE 1%
J 0
(5125 2625);
DISPLAY 0.510638 (5125 2625);
PAINT SKYBLUE (5125 2625);
FORCEPROP 2 LAST CDS_LIB pure_quanta
J 0
(4900 2675);
DISPLAY INVISIBLE (4900 2675);
FORCEPROP 2 LAST SEC_TYPE 0402LF
J 0
(4850 2875);
DISPLAY 0.680851 (4850 2875);
DISPLAY INVISIBLE (4850 2875);
FORCEPROP 1 LAST PATH I237
J 0
(4850 2825);
DISPLAY 0.978723 (4850 2825);
PAINT WHITE (4850 2825);
DISPLAY INVISIBLE (4850 2825);
FORCEPROP 1 LAST PART_NUMBER CS03322FB03
J 0
(5025 2725);
DISPLAY 0.510638 (5025 2725);
PAINT WHITE (5025 2725);
DISPLAY INVISIBLE (5025 2725);
FORCEPROP 1 LAST LOCATION R766
J 0
(4800 2600);
DISPLAY 0.702128 (4800 2600);
PAINT YELLOW (4800 2600);
FORCEPROP 1 LASTPIN (4800 2675) $PN 1
J 0
(4812 2687);
DISPLAY 0.808511 (4812 2687);
PAINT WHITE (4812 2687);
FORCEPROP 1 LASTPIN (5000 2675) $PN 2
J 0
(4965 2685);
DISPLAY 0.808511 (4965 2685);
PAINT WHITE (4965 2685);
FORCEPROP 2 LAST SEC 1
J 0
(4850 2875);
DISPLAY 0.680851 (4850 2875);
PAINT MONO (4850 2875);
DISPLAY INVISIBLE (4850 2875);
FORCEADD UNIVERSAL_POWER..1
(3675 1525);
FORCEPROP 3 LASTPIN (3675 1475) SIG_NAME P3V3_AUX\g
J 0
(3685 1485);
DISPLAY 0.659574 (3685 1485);
PAINT MONO (3685 1485);
DISPLAY INVISIBLE (3685 1485);
FORCEPROP 1 LAST HDL_POWER P3V3_AUX
J 1
(3675 1575);
DISPLAY 0.702128 (3675 1575);
PAINT PEACH (3675 1575);
FORCEPROP 1 LAST PATH I238
J 0
(3725 1550);
DISPLAY 0.872340 (3725 1550);
PAINT AQUA (3725 1550);
DISPLAY INVISIBLE (3725 1550);
FORCEPROP 2 LAST CDS_LIB logical_power
J 0
(3675 1525);
DISPLAY INVISIBLE (3675 1525);
FORCEADD Q_RES..2
R 2
(3675 1250);
FORCEPROP 1 LAST MATERIAL CHIP
J 2
(3635 1175);
DISPLAY 0.510638 (3635 1175);
PAINT SKYBLUE (3635 1175);
FORCEPROP 1 LAST PART_NUMBER CS24702FB06
J 2
(3635 1125);
DISPLAY 0.510638 (3635 1125);
PAINT WHITE (3635 1125);
FORCEPROP 1 LAST PACK_TYPE 0402LF
J 2
(3635 1075);
DISPLAY 0.510638 (3635 1075);
PAINT SKYBLUE (3635 1075);
FORCEPROP 1 LAST TOLERANCE 1%
J 2
(3630 1275);
DISPLAY 0.510638 (3630 1275);
PAINT SKYBLUE (3630 1275);
FORCEPROP 1 LAST WATTAGE 1/16W
J 2
(3635 1225);
DISPLAY 0.510638 (3635 1225);
PAINT SKYBLUE (3635 1225);
FORCEPROP 1 LAST VALUE 4.7K
J 2
(3630 1325);
DISPLAY 0.510638 (3630 1325);
PAINT SKYBLUE (3630 1325);
FORCEPROP 1 LAST PATH I239
J 2
(3625 1425);
DISPLAY 0.978723 (3625 1425);
PAINT WHITE (3625 1425);
DISPLAY INVISIBLE (3625 1425);
FORCEPROP 2 LAST SEC_TYPE 0402LF
J 0
(3625 1475);
DISPLAY 0.680851 (3625 1475);
DISPLAY INVISIBLE (3625 1475);
FORCEPROP 2 LAST CDS_LIB pure_quanta
J 2
(3675 1250);
PAINT MONO (3675 1250);
DISPLAY INVISIBLE (3675 1250);
FORCEPROP 1 LAST LOCATION R765
J 2
(3630 1375);
DISPLAY 0.702128 (3630 1375);
PAINT YELLOW (3630 1375);
FORCEPROP 1 LASTPIN (3675 1350) $PN 1
J 2
(3670 1312);
DISPLAY 0.808511 (3670 1312);
PAINT WHITE (3670 1312);
FORCEPROP 1 LASTPIN (3675 1150) $PN 2
J 2
(3670 1160);
DISPLAY 0.808511 (3670 1160);
PAINT WHITE (3670 1160);
FORCEPROP 2 LAST SEC 1
J 0
(3625 1475);
DISPLAY 0.680851 (3625 1475);
PAINT MONO (3625 1475);
DISPLAY INVISIBLE (3625 1475);
FORCEADD 74LVC2G07DW7..1
(1425 900);
FORCEPROP 1 LAST PART_NUMBER AL002G07003
J 0
(1256 1134);
DISPLAY 0.723404 (1256 1134);
PAINT GREEN (1256 1134);
FORCEPROP 2 LAST VALUE 74LVC2G07DW-7
J 0
(1275 1325);
DISPLAY 0.680851 (1275 1325);
FORCEPROP 2 LAST PART_TYPE SMLF
J 0
(1275 1375);
DISPLAY 0.680851 (1275 1375);
FORCEPROP 1 LAST MATERIAL IC
J 0
(1256 1007);
DISPLAY 0.723404 (1256 1007);
PAINT GREEN (1256 1007);
FORCEPROP 1 LAST NEEDS_NO_SIZE TRUE
J 0
(1425 900);
DISPLAY 0.723404 (1425 900);
PAINT GREEN (1425 900);
DISPLAY INVISIBLE (1425 900);
FORCEPROP 1 LAST CDS_LMAN_SYM_OUTLINE -175,100,175,-100
J 0
(1425 900);
DISPLAY 0.468085 (1425 900);
PAINT GREEN (1425 900);
DISPLAY INVISIBLE (1425 900);
FORCEPROP 1 LAST PATH I246
J 0
(1425 900);
DISPLAY 0.723404 (1425 900);
PAINT GREEN (1425 900);
DISPLAY INVISIBLE (1425 900);
FORCEPROP 2 LAST CDS_LIB pure_quanta
J 0
(1425 900);
DISPLAY INVISIBLE (1425 900);
FORCEPROP 1 LAST LOCATION U24
J 0
(1256 1281);
DISPLAY 0.723404 (1256 1281);
PAINT GREEN (1256 1281);
FORCEPROP 0 LASTPIN (1100 950) $PN 1
J 2
(1090 960);
DISPLAY 0.680851 (1090 960);
PAINT MONO (1090 960);
FORCEPROP 0 LASTPIN (1750 950) $PN 6
J 0
(1760 960);
DISPLAY 0.680851 (1760 960);
PAINT MONO (1760 960);
FORCEPROP 0 LASTPIN (1100 850) $PN 3
J 2
(1090 860);
DISPLAY 0.680851 (1090 860);
PAINT MONO (1090 860);
FORCEPROP 0 LASTPIN (1750 850) $PN 4
J 0
(1760 860);
DISPLAY 0.680851 (1760 860);
PAINT MONO (1760 860);
FORCEPROP 0 LASTPIN (1100 900) $PN 2
J 2
(1090 910);
DISPLAY 0.680851 (1090 910);
PAINT MONO (1090 910);
FORCEPROP 0 LASTPIN (1750 900) $PN 5
J 0
(1760 910);
DISPLAY 0.680851 (1760 910);
PAINT MONO (1760 910);
FORCEPROP 0 LAST $SEC 1
J 0
(1275 1425);
DISPLAY 0.680851 (1275 1425);
PAINT MONO (1275 1425);
DISPLAY INVISIBLE (1275 1425);
FORCEPROP 0 LAST CDS_SEC 1
J 0
(1275 1425);
DISPLAY 0.680851 (1275 1425);
DISPLAY INVISIBLE (1275 1425);
FORCEADD 74LVC2G07DW7..1
(-250 2100);
FORCEPROP 2 LAST VALUE 74LVC2G07DW-7
J 0
(-400 2525);
DISPLAY 0.680851 (-400 2525);
FORCEPROP 1 LAST MATERIAL IC
J 0
(-419 2207);
DISPLAY 0.723404 (-419 2207);
PAINT GREEN (-419 2207);
FORCEPROP 1 LAST PART_NUMBER AL002G07003
J 0
(-419 2334);
DISPLAY 0.723404 (-419 2334);
PAINT GREEN (-419 2334);
FORCEPROP 2 LAST PART_TYPE SMLF
J 0
(-400 2575);
DISPLAY 0.680851 (-400 2575);
FORCEPROP 1 LAST NEEDS_NO_SIZE TRUE
J 0
(-250 2100);
DISPLAY 0.723404 (-250 2100);
PAINT GREEN (-250 2100);
DISPLAY INVISIBLE (-250 2100);
FORCEPROP 1 LAST CDS_LMAN_SYM_OUTLINE -175,100,175,-100
J 0
(-250 2100);
DISPLAY 0.468085 (-250 2100);
PAINT GREEN (-250 2100);
DISPLAY INVISIBLE (-250 2100);
FORCEPROP 1 LAST PATH I247
J 0
(-250 2100);
DISPLAY 0.723404 (-250 2100);
PAINT GREEN (-250 2100);
DISPLAY INVISIBLE (-250 2100);
FORCEPROP 2 LAST CDS_LIB pure_quanta
J 0
(-250 2100);
DISPLAY INVISIBLE (-250 2100);
FORCEPROP 1 LAST LOCATION U47
J 0
(-419 2481);
DISPLAY 0.723404 (-419 2481);
PAINT GREEN (-419 2481);
FORCEPROP 0 LASTPIN (-575 2150) $PN 1
J 2
(-585 2160);
DISPLAY 0.680851 (-585 2160);
PAINT MONO (-585 2160);
FORCEPROP 0 LASTPIN (75 2150) $PN 6
J 0
(85 2160);
DISPLAY 0.680851 (85 2160);
PAINT MONO (85 2160);
FORCEPROP 0 LASTPIN (-575 2050) $PN 3
J 2
(-585 2060);
DISPLAY 0.680851 (-585 2060);
PAINT MONO (-585 2060);
FORCEPROP 0 LASTPIN (75 2050) $PN 4
J 0
(85 2060);
DISPLAY 0.680851 (85 2060);
PAINT MONO (85 2060);
FORCEPROP 0 LASTPIN (-575 2100) $PN 2
J 2
(-585 2110);
DISPLAY 0.680851 (-585 2110);
PAINT MONO (-585 2110);
FORCEPROP 0 LASTPIN (75 2100) $PN 5
J 0
(85 2110);
DISPLAY 0.680851 (85 2110);
PAINT MONO (85 2110);
FORCEPROP 0 LAST $SEC 1
J 0
(-400 2625);
DISPLAY 0.680851 (-400 2625);
PAINT MONO (-400 2625);
DISPLAY INVISIBLE (-400 2625);
FORCEPROP 0 LAST CDS_SEC 1
J 0
(-400 2625);
DISPLAY 0.680851 (-400 2625);
DISPLAY INVISIBLE (-400 2625);
FORCEADD FSA3357K8X..1
R 2
(3600 4100);
FORCEPROP 1 LAST MATERIAL IC
J 2
(3753 4330);
DISPLAY 0.723404 (3753 4330);
PAINT GREEN (3753 4330);
FORCEPROP 2 LAST VALUE FSA3357K8X
J 2
(3750 4550);
DISPLAY 0.680851 (3750 4550);
FORCEPROP 1 LAST PART_NUMBER AL003357009
J 2
(3753 4419);
DISPLAY 0.723404 (3753 4419);
PAINT GREEN (3753 4419);
FORCEPROP 2 LAST PART_TYPE SMLF
J 2
(3750 4600);
DISPLAY 0.680851 (3750 4600);
FORCEPROP 1 LAST CDS_LMAN_SYM_OUTLINE -150,225,150,-225
J 2
(3600 4100);
DISPLAY 0.468085 (3600 4100);
PAINT GREEN (3600 4100);
DISPLAY INVISIBLE (3600 4100);
FORCEPROP 1 LAST PIN_NAMES_ROTATE True
J 2
(3600 4100);
DISPLAY 0.489362 (3600 4100);
PAINT GREEN (3600 4100);
DISPLAY INVISIBLE (3600 4100);
FORCEPROP 1 LAST PATH I250
J 2
(3600 4100);
DISPLAY 0.723404 (3600 4100);
PAINT GREEN (3600 4100);
DISPLAY INVISIBLE (3600 4100);
FORCEPROP 2 LAST CDS_LIB pure_quanta
J 2
(3600 4100);
DISPLAY INVISIBLE (3600 4100);
FORCEPROP 1 LAST LOCATION U2
J 2
(3753 4503);
DISPLAY 0.723404 (3753 4503);
PAINT GREEN (3753 4503);
FORCEPROP 0 LASTPIN (3300 4175) $PN 7
J 2
(3290 4185);
DISPLAY 0.680851 (3290 4185);
PAINT MONO (3290 4185);
FORCEPROP 0 LASTPIN (3900 4125) $PN 1
J 0
(3910 4135);
DISPLAY 0.680851 (3910 4135);
PAINT MONO (3910 4135);
FORCEPROP 0 LASTPIN (3900 4175) $PN 2
J 0
(3910 4185);
DISPLAY 0.680851 (3910 4185);
PAINT MONO (3910 4185);
FORCEPROP 0 LASTPIN (3900 4225) $PN 3
J 0
(3910 4235);
DISPLAY 0.680851 (3910 4235);
PAINT MONO (3910 4235);
FORCEPROP 0 LASTPIN (3900 3925) $PN 4
J 0
(3910 3935);
DISPLAY 0.680851 (3910 3935);
PAINT MONO (3910 3935);
FORCEPROP 0 LASTPIN (3300 4025) $PN 6
J 2
(3290 4035);
DISPLAY 0.680851 (3290 4035);
PAINT MONO (3290 4035);
FORCEPROP 0 LASTPIN (3300 4075) $PN 5
J 2
(3290 4085);
DISPLAY 0.680851 (3290 4085);
PAINT MONO (3290 4085);
FORCEPROP 0 LASTPIN (3300 4275) $PN 8
J 2
(3290 4285);
DISPLAY 0.680851 (3290 4285);
PAINT MONO (3290 4285);
FORCEPROP 0 LAST $SEC 1
J 0
(3750 4650);
DISPLAY 0.680851 (3750 4650);
PAINT MONO (3750 4650);
DISPLAY INVISIBLE (3750 4650);
FORCEPROP 0 LAST CDS_SEC 1
J 0
(3750 4650);
DISPLAY 0.680851 (3750 4650);
DISPLAY INVISIBLE (3750 4650);
FORCEADD FSA3357K8X..1
R 2
(3425 3125);
FORCEPROP 1 LAST MATERIAL IC
J 2
(3578 3355);
DISPLAY 0.723404 (3578 3355);
PAINT GREEN (3578 3355);
FORCEPROP 2 LAST PART_TYPE SMLF
J 2
(3575 3625);
DISPLAY 0.680851 (3575 3625);
FORCEPROP 1 LAST PART_NUMBER AL003357009
J 2
(3578 3444);
DISPLAY 0.723404 (3578 3444);
PAINT GREEN (3578 3444);
FORCEPROP 2 LAST VALUE FSA3357K8X
J 2
(3575 3575);
DISPLAY 0.680851 (3575 3575);
FORCEPROP 2 LAST CDS_LIB pure_quanta
J 2
(3425 3125);
DISPLAY INVISIBLE (3425 3125);
FORCEPROP 1 LAST PATH I251
J 2
(3425 3125);
DISPLAY 0.723404 (3425 3125);
PAINT GREEN (3425 3125);
DISPLAY INVISIBLE (3425 3125);
FORCEPROP 1 LAST PIN_NAMES_ROTATE True
J 2
(3425 3125);
DISPLAY 0.489362 (3425 3125);
PAINT GREEN (3425 3125);
DISPLAY INVISIBLE (3425 3125);
FORCEPROP 1 LAST CDS_LMAN_SYM_OUTLINE -150,225,150,-225
J 2
(3425 3125);
DISPLAY 0.468085 (3425 3125);
PAINT GREEN (3425 3125);
DISPLAY INVISIBLE (3425 3125);
FORCEPROP 1 LAST LOCATION U3
J 2
(3578 3528);
DISPLAY 0.723404 (3578 3528);
PAINT GREEN (3578 3528);
FORCEPROP 0 LASTPIN (3125 3200) $PN 7
J 2
(3115 3210);
DISPLAY 0.680851 (3115 3210);
PAINT MONO (3115 3210);
FORCEPROP 0 LASTPIN (3725 3150) $PN 1
J 0
(3735 3160);
DISPLAY 0.680851 (3735 3160);
PAINT MONO (3735 3160);
FORCEPROP 0 LASTPIN (3725 3200) $PN 2
J 0
(3735 3210);
DISPLAY 0.680851 (3735 3210);
PAINT MONO (3735 3210);
FORCEPROP 0 LASTPIN (3725 3250) $PN 3
J 0
(3735 3260);
DISPLAY 0.680851 (3735 3260);
PAINT MONO (3735 3260);
FORCEPROP 0 LASTPIN (3725 2950) $PN 4
J 0
(3735 2960);
DISPLAY 0.680851 (3735 2960);
PAINT MONO (3735 2960);
FORCEPROP 0 LASTPIN (3125 3050) $PN 6
J 2
(3115 3060);
DISPLAY 0.680851 (3115 3060);
PAINT MONO (3115 3060);
FORCEPROP 0 LASTPIN (3125 3100) $PN 5
J 2
(3115 3110);
DISPLAY 0.680851 (3115 3110);
PAINT MONO (3115 3110);
FORCEPROP 0 LASTPIN (3125 3300) $PN 8
J 2
(3115 3310);
DISPLAY 0.680851 (3115 3310);
PAINT MONO (3115 3310);
FORCEPROP 0 LAST $SEC 1
J 0
(3575 3675);
DISPLAY 0.680851 (3575 3675);
PAINT MONO (3575 3675);
DISPLAY INVISIBLE (3575 3675);
FORCEPROP 0 LAST CDS_SEC 1
J 0
(3575 3675);
DISPLAY 0.680851 (3575 3675);
DISPLAY INVISIBLE (3575 3675);
FORCEADD OFFPAGE..4
(4875 4125);
FORCEPROP 2 LAST $XR0 31 
J 0
(5061 4125);
DISPLAY 0.638298 (5061 4125);
PAINT MONO (5061 4125);
FORCEPROP 2 LAST PATH I252
J 0
(5075 4175);
DISPLAY 0.680851 (5075 4175);
DISPLAY INVISIBLE (5075 4175);
FORCEPROP 1 LAST COMMENT_BODY TRUE
J 0
(4850 4025);
DISPLAY 0.872340 (4850 4025);
PAINT PEACH (4850 4025);
DISPLAY INVISIBLE (4850 4025);
FORCEPROP 1 LAST OFFPAGE TRUE
J 0
(5200 4000);
DISPLAY 0.872340 (5200 4000);
PAINT GREEN (5200 4000);
DISPLAY INVISIBLE (5200 4000);
FORCEPROP 2 LAST CDS_LIB standard
J 0
(4875 4125);
DISPLAY 0.808511 (4875 4125);
PAINT MONO (4875 4125);
DISPLAY INVISIBLE (4875 4125);
FORCEADD UNIVERSAL_GND..1
(2825 3375);
FORCEPROP 3 LASTPIN (2825 3425) SIG_NAME GND\g
J 0
(2835 3435);
DISPLAY 0.659574 (2835 3435);
PAINT MONO (2835 3435);
DISPLAY INVISIBLE (2835 3435);
FORCEPROP 1 LAST PATH I253
J 0
(2900 3375);
DISPLAY 0.872340 (2900 3375);
PAINT AQUA (2900 3375);
DISPLAY INVISIBLE (2900 3375);
FORCEPROP 1 LAST HDL_POWER GND
J 1
(2850 3300);
DISPLAY 0.702128 (2850 3300);
PAINT GREEN (2850 3300);
DISPLAY INVISIBLE (2850 3300);
FORCEPROP 2 LAST CDS_LIB logical_power
J 0
(2825 3375);
DISPLAY INVISIBLE (2825 3375);
FORCEADD Q_CAP..1
(2825 3575);
FORCEPROP 1 LAST VOLTAGE 25V
J 0
(2875 3575);
DISPLAY 0.510638 (2875 3575);
PAINT SKYBLUE (2875 3575);
FORCEPROP 1 LAST VALUE 0.1UF
J 0
(2875 3625);
DISPLAY 0.510638 (2875 3625);
PAINT SKYBLUE (2875 3625);
FORCEPROP 1 LAST TOLERANCE 10%
J 0
(2875 3525);
DISPLAY 0.510638 (2875 3525);
PAINT SKYBLUE (2875 3525);
FORCEPROP 1 LAST MATERIAL X7R
J 0
(2875 3475);
DISPLAY 0.510638 (2875 3475);
PAINT SKYBLUE (2875 3475);
FORCEPROP 1 LAST PACK_TYPE 0402
J 0
(2875 3375);
DISPLAY 0.510638 (2875 3375);
PAINT SKYBLUE (2875 3375);
FORCEPROP 1 LAST PART_NUMBER CH4104K1B00
J 0
(2875 3425);
DISPLAY 0.510638 (2875 3425);
PAINT WHITE (2875 3425);
FORCEPROP 1 LAST PATH I254
J 0
(2875 3725);
DISPLAY 0.978723 (2875 3725);
PAINT WHITE (2875 3725);
DISPLAY INVISIBLE (2875 3725);
FORCEPROP 2 LAST SEC_TYPE 0402
J 0
(2875 3775);
DISPLAY 1.021277 (2875 3775);
DISPLAY INVISIBLE (2875 3775);
FORCEPROP 2 LAST CDS_LIB pure_quanta
J 0
(2825 3575);
DISPLAY INVISIBLE (2825 3575);
FORCEPROP 1 LAST LOCATION C20
J 0
(2875 3675);
DISPLAY 0.702128 (2875 3675);
PAINT YELLOW (2875 3675);
FORCEPROP 1 LASTPIN (2825 3675) $PN 1
J 0
(2835 3655);
DISPLAY 0.808511 (2835 3655);
PAINT WHITE (2835 3655);
FORCEPROP 1 LASTPIN (2825 3475) $PN 2
J 0
(2835 3455);
DISPLAY 0.808511 (2835 3455);
PAINT WHITE (2835 3455);
FORCEPROP 2 LAST SEC 1
J 0
(2875 3775);
DISPLAY 0.680851 (2875 3775);
PAINT MONO (2875 3775);
DISPLAY INVISIBLE (2875 3775);
FORCEADD UNIVERSAL_POWER..1
(2650 3850);
FORCEPROP 3 LASTPIN (2650 3800) SIG_NAME P3V3_AUX\g
J 0
(2660 3810);
DISPLAY 0.659574 (2660 3810);
PAINT MONO (2660 3810);
DISPLAY INVISIBLE (2660 3810);
FORCEPROP 1 LAST HDL_POWER P3V3_AUX
J 1
(2650 3900);
DISPLAY 0.702128 (2650 3900);
PAINT PEACH (2650 3900);
FORCEPROP 1 LAST PATH I255
J 0
(2700 3875);
DISPLAY 0.872340 (2700 3875);
PAINT AQUA (2700 3875);
DISPLAY INVISIBLE (2700 3875);
FORCEPROP 2 LAST CDS_LIB logical_power
J 0
(2650 3850);
DISPLAY INVISIBLE (2650 3850);
FORCEADD UNIVERSAL_GND..1
(3850 2825);
FORCEPROP 3 LASTPIN (3850 2875) SIG_NAME GND\g
J 0
(3860 2885);
DISPLAY 0.659574 (3860 2885);
PAINT MONO (3860 2885);
DISPLAY INVISIBLE (3860 2885);
FORCEPROP 1 LAST HDL_POWER GND
J 1
(3875 2750);
DISPLAY 0.702128 (3875 2750);
PAINT GREEN (3875 2750);
DISPLAY INVISIBLE (3875 2750);
FORCEPROP 1 LAST PATH I256
J 0
(3925 2825);
DISPLAY 0.872340 (3925 2825);
PAINT AQUA (3925 2825);
DISPLAY INVISIBLE (3925 2825);
FORCEPROP 2 LAST CDS_LIB logical_power
J 0
(3850 2825);
DISPLAY INVISIBLE (3850 2825);
FORCEADD OFFPAGE..4
R 2
(2475 4075);
FORCEPROP 2 LAST $XR0 36 
J 0
(2254 4075);
DISPLAY 0.638298 (2254 4075);
PAINT MONO (2254 4075);
FORCEPROP 2 LAST $XR1 30 
J 0
(2164 4075);
DISPLAY 0.638298 (2164 4075);
PAINT MONO (2164 4075);
FORCEPROP 2 LAST $XR2 49 
J 0
(2074 4075);
DISPLAY 0.638298 (2074 4075);
PAINT MONO (2074 4075);
FORCEPROP 2 LAST CDS_LIB standard
J 2
(2475 4075);
DISPLAY 0.808511 (2475 4075);
PAINT MONO (2475 4075);
DISPLAY INVISIBLE (2475 4075);
FORCEPROP 1 LAST OFFPAGE TRUE
J 2
(2150 3950);
DISPLAY 0.872340 (2150 3950);
PAINT GREEN (2150 3950);
DISPLAY INVISIBLE (2150 3950);
FORCEPROP 1 LAST COMMENT_BODY TRUE
J 2
(2500 3975);
DISPLAY 0.872340 (2500 3975);
PAINT PEACH (2500 3975);
DISPLAY INVISIBLE (2500 3975);
FORCEPROP 2 LAST PATH I258
J 0
(2275 4125);
DISPLAY 0.680851 (2275 4125);
DISPLAY INVISIBLE (2275 4125);
FORCEADD OFFPAGE..4
R 2
(2475 4025);
FORCEPROP 2 LAST $XR2 49 
J 0
(2074 4025);
DISPLAY 0.638298 (2074 4025);
PAINT MONO (2074 4025);
FORCEPROP 2 LAST $XR1 30 
J 0
(2164 4025);
DISPLAY 0.638298 (2164 4025);
PAINT MONO (2164 4025);
FORCEPROP 2 LAST $XR0 36 
J 0
(2254 4025);
DISPLAY 0.638298 (2254 4025);
PAINT MONO (2254 4025);
FORCEPROP 1 LAST COMMENT_BODY TRUE
J 2
(2500 3925);
DISPLAY 0.872340 (2500 3925);
PAINT PEACH (2500 3925);
DISPLAY INVISIBLE (2500 3925);
FORCEPROP 1 LAST OFFPAGE TRUE
J 2
(2150 3900);
DISPLAY 0.872340 (2150 3900);
PAINT GREEN (2150 3900);
DISPLAY INVISIBLE (2150 3900);
FORCEPROP 2 LAST CDS_LIB standard
J 2
(2475 4025);
DISPLAY 0.808511 (2475 4025);
PAINT MONO (2475 4025);
DISPLAY INVISIBLE (2475 4025);
FORCEPROP 2 LAST PATH I259
J 0
(2275 4075);
DISPLAY 0.680851 (2275 4075);
DISPLAY INVISIBLE (2275 4075);
FORCEADD UNIVERSAL_POWER..1
(2825 4825);
FORCEPROP 3 LASTPIN (2825 4775) SIG_NAME P3V3_AUX\g
J 0
(2835 4785);
DISPLAY 0.659574 (2835 4785);
PAINT MONO (2835 4785);
DISPLAY INVISIBLE (2835 4785);
FORCEPROP 1 LAST HDL_POWER P3V3_AUX
J 1
(2825 4875);
DISPLAY 0.702128 (2825 4875);
PAINT PEACH (2825 4875);
FORCEPROP 2 LAST CDS_LIB logical_power
J 0
(2825 4825);
DISPLAY INVISIBLE (2825 4825);
FORCEPROP 1 LAST PATH I260
J 0
(2875 4850);
DISPLAY 0.872340 (2875 4850);
PAINT AQUA (2875 4850);
DISPLAY INVISIBLE (2875 4850);
FORCEADD Q_CAP..1
(3000 4550);
FORCEPROP 1 LAST PACK_TYPE 0402
J 0
(3050 4350);
DISPLAY 0.510638 (3050 4350);
PAINT SKYBLUE (3050 4350);
FORCEPROP 1 LAST VALUE 0.1UF
J 0
(3050 4600);
DISPLAY 0.510638 (3050 4600);
PAINT SKYBLUE (3050 4600);
FORCEPROP 1 LAST MATERIAL X7R
J 0
(3050 4450);
DISPLAY 0.510638 (3050 4450);
PAINT SKYBLUE (3050 4450);
FORCEPROP 1 LAST VOLTAGE 25V
J 0
(3050 4550);
DISPLAY 0.510638 (3050 4550);
PAINT SKYBLUE (3050 4550);
FORCEPROP 1 LAST TOLERANCE 10%
J 0
(3050 4500);
DISPLAY 0.510638 (3050 4500);
PAINT SKYBLUE (3050 4500);
FORCEPROP 1 LAST PART_NUMBER CH4104K1B00
J 0
(3050 4400);
DISPLAY 0.510638 (3050 4400);
PAINT WHITE (3050 4400);
FORCEPROP 2 LAST CDS_LIB pure_quanta
J 0
(3000 4550);
DISPLAY INVISIBLE (3000 4550);
FORCEPROP 2 LAST SEC_TYPE 0402
J 0
(3050 4750);
DISPLAY 1.021277 (3050 4750);
DISPLAY INVISIBLE (3050 4750);
FORCEPROP 1 LAST PATH I261
J 0
(3050 4700);
DISPLAY 0.978723 (3050 4700);
PAINT WHITE (3050 4700);
DISPLAY INVISIBLE (3050 4700);
FORCEPROP 1 LAST LOCATION C19
J 0
(3050 4650);
DISPLAY 0.702128 (3050 4650);
PAINT YELLOW (3050 4650);
FORCEPROP 1 LASTPIN (3000 4650) $PN 1
J 0
(3010 4630);
DISPLAY 0.808511 (3010 4630);
PAINT WHITE (3010 4630);
FORCEPROP 1 LASTPIN (3000 4450) $PN 2
J 0
(3010 4430);
DISPLAY 0.808511 (3010 4430);
PAINT WHITE (3010 4430);
FORCEPROP 2 LAST SEC 1
J 0
(3050 4750);
DISPLAY 0.680851 (3050 4750);
PAINT MONO (3050 4750);
DISPLAY INVISIBLE (3050 4750);
FORCEADD UNIVERSAL_GND..1
(3000 4350);
FORCEPROP 3 LASTPIN (3000 4400) SIG_NAME GND\g
J 0
(3010 4410);
DISPLAY 0.659574 (3010 4410);
PAINT MONO (3010 4410);
DISPLAY INVISIBLE (3010 4410);
FORCEPROP 2 LAST CDS_LIB logical_power
J 0
(3000 4350);
DISPLAY INVISIBLE (3000 4350);
FORCEPROP 1 LAST HDL_POWER GND
J 1
(3025 4275);
DISPLAY 0.702128 (3025 4275);
PAINT GREEN (3025 4275);
DISPLAY INVISIBLE (3025 4275);
FORCEPROP 1 LAST PATH I262
J 0
(3075 4350);
DISPLAY 0.872340 (3075 4350);
PAINT AQUA (3075 4350);
DISPLAY INVISIBLE (3075 4350);
FORCEADD OFFPAGE..4
R 2
(2375 3100);
FORCEPROP 2 LAST $XR0 36 
J 0
(2124 3100);
DISPLAY 0.638298 (2124 3100);
PAINT MONO (2124 3100);
FORCEPROP 2 LAST $XR2 49 
J 0
(1944 3100);
DISPLAY 0.638298 (1944 3100);
PAINT MONO (1944 3100);
FORCEPROP 2 LAST $XR1 30 
J 0
(2034 3100);
DISPLAY 0.638298 (2034 3100);
PAINT MONO (2034 3100);
FORCEPROP 2 LAST PATH I263
J 0
(2175 3150);
DISPLAY 0.680851 (2175 3150);
DISPLAY INVISIBLE (2175 3150);
FORCEPROP 1 LAST COMMENT_BODY TRUE
J 2
(2400 3000);
DISPLAY 0.872340 (2400 3000);
PAINT PEACH (2400 3000);
DISPLAY INVISIBLE (2400 3000);
FORCEPROP 1 LAST OFFPAGE TRUE
J 2
(2050 2975);
DISPLAY 0.872340 (2050 2975);
PAINT GREEN (2050 2975);
DISPLAY INVISIBLE (2050 2975);
FORCEPROP 2 LAST CDS_LIB standard
J 2
(2375 3100);
DISPLAY 0.808511 (2375 3100);
PAINT MONO (2375 3100);
DISPLAY INVISIBLE (2375 3100);
FORCEADD OFFPAGE..4
R 2
(2375 3050);
FORCEPROP 2 LAST $XR0 36 
J 0
(2124 3050);
DISPLAY 0.638298 (2124 3050);
PAINT MONO (2124 3050);
FORCEPROP 2 LAST $XR1 30 
J 0
(2034 3050);
DISPLAY 0.638298 (2034 3050);
PAINT MONO (2034 3050);
FORCEPROP 2 LAST $XR2 49 
J 0
(1944 3050);
DISPLAY 0.638298 (1944 3050);
PAINT MONO (1944 3050);
FORCEPROP 2 LAST PATH I264
J 0
(2175 3100);
DISPLAY 0.680851 (2175 3100);
DISPLAY INVISIBLE (2175 3100);
FORCEPROP 2 LAST CDS_LIB standard
J 2
(2375 3050);
DISPLAY 0.808511 (2375 3050);
PAINT MONO (2375 3050);
DISPLAY INVISIBLE (2375 3050);
FORCEPROP 1 LAST OFFPAGE TRUE
J 2
(2050 2925);
DISPLAY 0.872340 (2050 2925);
PAINT GREEN (2050 2925);
DISPLAY INVISIBLE (2050 2925);
FORCEPROP 1 LAST COMMENT_BODY TRUE
J 2
(2400 2950);
DISPLAY 0.872340 (2400 2950);
PAINT PEACH (2400 2950);
DISPLAY INVISIBLE (2400 2950);
FORCEADD OFFPAGE..2
(4700 3150);
FORCEPROP 2 LAST $XR0 31 
J 0
(4889 3150);
DISPLAY 0.638298 (4889 3150);
PAINT MONO (4889 3150);
FORCEPROP 2 LAST CDS_LIB standard
J 0
(4700 3150);
DISPLAY INVISIBLE (4700 3150);
FORCEPROP 2 LAST PATH I265
J 0
(4875 3225);
DISPLAY 0.680851 (4875 3225);
DISPLAY INVISIBLE (4875 3225);
FORCEPROP 1 LAST OFFPAGE TRUE
J 0
(5025 3025);
DISPLAY 0.872340 (5025 3025);
PAINT GREEN (5025 3025);
DISPLAY INVISIBLE (5025 3025);
FORCEPROP 1 LAST COMMENT_BODY TRUE
J 0
(4655 3055);
DISPLAY 0.872340 (4655 3055);
PAINT PEACH (4655 3055);
DISPLAY INVISIBLE (4655 3055);
FORCEADD Q_RES..1
(350 3200);
FORCEPROP 1 LAST PACK_TYPE 0402LF
J 0
(475 3175);
DISPLAY 0.510638 (475 3175);
PAINT SKYBLUE (475 3175);
FORCEPROP 1 LAST VALUE 0
J 2
(500 3200);
DISPLAY 0.510638 (500 3200);
PAINT SKYBLUE (500 3200);
FORCEPROP 1 LAST PART_NUMBER CS00002JB13
J 0
(225 3250);
DISPLAY 0.510638 (225 3250);
PAINT WHITE (225 3250);
FORCEPROP 1 LAST MATERIAL CHIP
J 0
(525 3200);
DISPLAY 0.510638 (525 3200);
PAINT SKYBLUE (525 3200);
FORCEPROP 1 LAST WATTAGE 1/16W
J 2
(325 3050);
DISPLAY 0.510638 (325 3050);
PAINT SKYBLUE (325 3050);
DISPLAY INVISIBLE (325 3050);
FORCEPROP 1 LAST TOLERANCE 5%
J 0
(350 3100);
DISPLAY 0.510638 (350 3100);
PAINT SKYBLUE (350 3100);
DISPLAY INVISIBLE (350 3100);
FORCEPROP 2 LAST CDS_LIB pure_quanta
J 0
(350 3200);
DISPLAY INVISIBLE (350 3200);
FORCEPROP 1 LAST PATH I266
J 0
(300 3350);
DISPLAY 0.978723 (300 3350);
PAINT WHITE (300 3350);
DISPLAY INVISIBLE (300 3350);
FORCEPROP 1 LAST LOCATION R726
J 0
(150 3200);
DISPLAY 0.702128 (150 3200);
PAINT YELLOW (150 3200);
FORCEPROP 1 LASTPIN (250 3200) $PN 1
J 0
(262 3212);
DISPLAY 0.808511 (262 3212);
PAINT WHITE (262 3212);
FORCEPROP 1 LASTPIN (450 3200) $PN 2
J 0
(412 3212);
DISPLAY 0.808511 (412 3212);
PAINT WHITE (412 3212);
FORCEPROP 2 LAST $SEC 1
J 0
(225 3425);
DISPLAY 0.680851 (225 3425);
PAINT MONO (225 3425);
DISPLAY INVISIBLE (225 3425);
FORCEPROP 0 LAST CDS_SEC 1
J 0
(225 3425);
DISPLAY 0.680851 (225 3425);
PAINT MONO (225 3425);
DISPLAY INVISIBLE (225 3425);
FORCEADD Q_RES..1
(475 4175);
FORCEPROP 1 LAST MATERIAL CHIP
J 0
(650 4175);
DISPLAY 0.510638 (650 4175);
PAINT SKYBLUE (650 4175);
FORCEPROP 1 LAST PACK_TYPE 0402LF
J 0
(600 4150);
DISPLAY 0.510638 (600 4150);
PAINT SKYBLUE (600 4150);
FORCEPROP 1 LAST VALUE 0
J 2
(625 4175);
DISPLAY 0.510638 (625 4175);
PAINT SKYBLUE (625 4175);
FORCEPROP 1 LAST PART_NUMBER CS00002JB13
J 0
(350 4225);
DISPLAY 0.510638 (350 4225);
PAINT WHITE (350 4225);
FORCEPROP 1 LAST PATH I267
J 0
(425 4325);
DISPLAY 0.978723 (425 4325);
PAINT WHITE (425 4325);
DISPLAY INVISIBLE (425 4325);
FORCEPROP 2 LAST CDS_LIB pure_quanta
J 0
(475 4175);
DISPLAY INVISIBLE (475 4175);
FORCEPROP 1 LAST TOLERANCE 5%
J 0
(475 4075);
DISPLAY 0.510638 (475 4075);
PAINT SKYBLUE (475 4075);
DISPLAY INVISIBLE (475 4075);
FORCEPROP 1 LAST WATTAGE 1/16W
J 2
(450 4025);
DISPLAY 0.510638 (450 4025);
PAINT SKYBLUE (450 4025);
DISPLAY INVISIBLE (450 4025);
FORCEPROP 1 LAST LOCATION R39
J 0
(275 4175);
DISPLAY 0.702128 (275 4175);
PAINT YELLOW (275 4175);
FORCEPROP 1 LASTPIN (375 4175) $PN 1
J 0
(387 4187);
DISPLAY 0.808511 (387 4187);
PAINT WHITE (387 4187);
FORCEPROP 1 LASTPIN (575 4175) $PN 2
J 0
(537 4187);
DISPLAY 0.808511 (537 4187);
PAINT WHITE (537 4187);
FORCEPROP 2 LAST $SEC 1
J 0
(350 4400);
DISPLAY 0.680851 (350 4400);
PAINT MONO (350 4400);
DISPLAY INVISIBLE (350 4400);
FORCEPROP 0 LAST CDS_SEC 1
J 0
(350 4400);
DISPLAY 0.680851 (350 4400);
PAINT MONO (350 4400);
DISPLAY INVISIBLE (350 4400);
FORCEADD QUANTA_TITLE_BLOCK_C..1
(5700 -1600);
FORCEPROP 0 LAST CDS_CON_LAST_MODIFIED Fri Aug 25 17:25:42 2023
J 0
(3815 -1585);
DISPLAY INVISIBLE (3815 -1585);
FORCEPROP 2 LAST Q_DEPT 
J 1
(1937 -1551);
DISPLAY 1.957447 (1937 -1551);
PAINT GREEN (1937 -1551);
FORCEPROP 1 LAST CUSTOM_TXT_CDS <CON_LAST_MODIFIED>
J 0
(3815 -1585);
DISPLAY 0.978723 (3815 -1585);
FORCEPROP 2 LAST CUSTOM_TXT_CDS <XR_PAGE_TITLE>
J 0
(-2190 3650);
DISPLAY 0.638298 (-2190 3650);
PAINT PINK (-2190 3650);
DISPLAY INVISIBLE (-2190 3650);
FORCEPROP 1 LAST CUSTOM_TXT_CDS <NAME_2>
J 0
(2525 -1550);
FORCEPROP 1 LAST CUSTOM_TXT_CDS <NAME_1>
J 0
(2525 -1425);
FORCEPROP 1 LAST CUSTOM_TXT_CDS <Q_NUMBER>
J 0
(4297 -1497);
DISPLAY 1.212766 (4297 -1497);
FORCEPROP 1 LAST CUSTOM_TXT_CDS <Q_PROJ>
J 0
(3318 -1498);
DISPLAY 1.212766 (3318 -1498);
FORCEPROP 1 LAST CUSTOM_TXT_CDS <Q_REV>
J 0
(5516 -1497);
DISPLAY 1.212766 (5516 -1497);
FORCEPROP 1 LAST CUSTOM_TXT_CDS <CON_PAGE_NUM> OF <CON_TOTAL_PAGES>
J 0
(5254 -1582);
DISPLAY 0.978723 (5254 -1582);
FORCEPROP 1 LAST Q_TITLE BMC DEBUG PORT 1/2
J 0
(-3641 -1574);
DISPLAY 2.446809 (-3641 -1574);
PAINT GREEN (-3641 -1574);
FORCEPROP 2 LAST CDS_XR_PAGE_TITLE CR-30 : @SCM_LIB.SCM(SCH_1):PAGE30
J 0
(-2190 3650);
DISPLAY 0.638298 (-2190 3650);
PAINT PINK (-2190 3650);
DISPLAY INVISIBLE (-2190 3650);
FORCEPROP 1 LAST CDS_LMAN_SYM_OUTLINE -9475,6775,100,-125
J 0
(5700 -1600);
DISPLAY 0.468085 (5700 -1600);
PAINT GREEN (5700 -1600);
DISPLAY INVISIBLE (5700 -1600);
FORCEPROP 2 LAST CDS_LIB pure_quanta
J 0
(5700 -1600);
DISPLAY INVISIBLE (5700 -1600);
FORCEPROP 2 LAST PAGE_BORDER TRUE
J 0
(-2190 3650);
DISPLAY 0.638298 (-2190 3650);
PAINT PINK (-2190 3650);
DISPLAY INVISIBLE (-2190 3650);
FORCEPROP 1 LAST COMMENT_BODY TRUE
J 0
(5712 -1613);
DISPLAY 0.978723 (5712 -1613);
PAINT PEACH (5712 -1613);
DISPLAY INVISIBLE (5712 -1613);
FORCEADD DNS..2
(-2250 925);
PAINT RED (-2250 925);
FORCEPROP 2 LAST CDS_LIB mstr_misc
J 0
(-2250 925);
DISPLAY INVISIBLE (-2250 925);
FORCEPROP 1 LAST COMMENT_BODY TRUE
R 1
J 0
(-2175 700);
DISPLAY 0.872340 (-2175 700);
PAINT PEACH (-2175 700);
DISPLAY INVISIBLE (-2175 700);
FORCEADD DESIGN_NOTE..1
(4150 4975);
FORCEPROP 1 LAST COMMENT_BODY TRUE
J 0
(4175 5075);
DISPLAY 0.978723 (4175 5075);
PAINT PEACH (4175 5075);
DISPLAY INVISIBLE (4175 5075);
FORCEPROP 2 LAST CDS_LIB logical_power
J 0
(4150 4975);
DISPLAY INVISIBLE (4150 4975);
FORCEADD DNS..2
(1700 4700);
PAINT RED (1700 4700);
FORCEPROP 2 LAST CDS_LIB mstr_misc
J 0
(1700 4700);
DISPLAY INVISIBLE (1700 4700);
FORCEPROP 1 LAST COMMENT_BODY TRUE
R 1
J 0
(1775 4475);
DISPLAY 0.872340 (1775 4475);
PAINT PEACH (1775 4475);
DISPLAY INVISIBLE (1775 4475);
FORCEADD DNS..2
(1550 3700);
PAINT RED (1550 3700);
FORCEPROP 1 LAST COMMENT_BODY TRUE
R 1
J 0
(1625 3475);
DISPLAY 0.872340 (1625 3475);
PAINT PEACH (1625 3475);
DISPLAY INVISIBLE (1625 3475);
FORCEPROP 2 LAST CDS_LIB mstr_misc
J 0
(1550 3700);
DISPLAY INVISIBLE (1550 3700);
WIRE 16 -1 (1525 3800)(1525 3950);
WIRE 16 -1 (1825 2550)(1825 2675);
WIRE 16 -1 (2650 3800)(2650 3750);
WIRE 16 -1 (175 2725)(175 2650);
WIRE 16 -1 (1675 4825)(1675 4875);
WIRE 16 -1 (850 1375)(850 1475);
WIRE 16 -1 (2825 4775)(2825 4725);
WIRE 16 -1 (1850 1525)(1850 1450);
WIRE 16 -1 (3675 1350)(3675 1475);
WIRE 16 -1 (2200 2475)(2200 2600);
WIRE 16 -1 (-825 2575)(-825 2675);
WIRE 16 -1 (3000 4400)(3000 4450);
WIRE 16 -1 (2825 3425)(2825 3475);
WIRE 16 -1 (3850 2875)(3850 2950);
WIRE 16 -1 (4025 3850)(4025 3925);
WIRE 16 -1 (-700 1850)(-700 2100);
WIRE 16 -1 (375 2400)(375 2325);
WIRE 16 -1 (-1850 925)(-1850 650);
WIRE 16 -1 (-2025 925)(-1850 925);
WIRE 16 -1 (975 650)(975 900);
WIRE 16 -1 (2050 1200)(2050 1125);
WIRE 16 -1 (4025 3925)(3900 3925);
WIRE 16 -1 (975 900)(1100 900);
WIRE 16 -1 (-700 2100)(-575 2100);
WIRE 16 -1 (3850 2950)(3725 2950);
WIRE 16 273 (-3575 2925)(2625 2925);
WIRE 16 273 (2625 2925)(2625 2425);
WIRE 16 273 (2625 2425)(5625 2425);
WIRE 16 -1 (-1625 2150)(-575 2150);
FORCEPROP 2 LAST SIG_NAME UART_BMC_5_TXD_R
J 0
(-1610 2160);
DISPLAY 0.808511 (-1610 2160);
WIRE 16 -1 (-1625 2050)(-825 2050);
FORCEPROP 2 LAST SIG_NAME UART_BMC_5_RXD_BUF1
J 2
(-885 2060);
DISPLAY 0.808511 (-885 2060);
WIRE 16 -1 (-825 2050)(-575 2050);
WIRE 16 -1 (-825 2375)(-825 2050);
WIRE 16 3135 (5600 1675)(-3600 1675);
WIRE 16 -1 (2050 1450)(2050 1400);
WIRE 16 -1 (1850 1450)(2050 1450);
WIRE 16 -1 (1850 1450)(1850 900);
WIRE 16 -1 (1750 900)(1850 900);
WIRE 16 -1 (2200 2275)(2200 2050);
WIRE 16 -1 (2200 2050)(3225 2050);
FORCEPROP 2 LAST SIG_NAME UART_BMC_5_RXD_R
J 2
(3015 2060);
DISPLAY 0.808511 (3015 2060);
WIRE 16 -1 (1375 2050)(2200 2050);
WIRE 16 -1 (1825 2350)(1825 2150);
WIRE 16 -1 (1825 2150)(3225 2150);
FORCEPROP 2 LAST SIG_NAME UART_BMC_5_TXD_BUF1_R
J 0
(2390 2160);
DISPLAY 0.808511 (2390 2160);
WIRE 16 -1 (1375 2150)(1825 2150);
WIRE 16 3135 (5600 550)(-3600 550);
WIRE 16 -1 (-2025 975)(-925 975);
FORCEPROP 2 LAST SIG_NAME UART_BMC_5_TXD_BUF_R
J 0
(-1760 985);
DISPLAY 0.808511 (-1760 985);
WIRE 16 -1 (4800 2675)(3925 2675);
FORCEPROP 2 LAST SIG_NAME UART_BMC_5_RXD_BUF1
J 0
(3985 2685);
DISPLAY 0.808511 (3985 2685);
WIRE 16 -1 (-575 4175)(375 4175);
FORCEPROP 2 LAST SIG_NAME SPA_SOUT_SW_BUF_R
J 0
(-535 4185);
DISPLAY 0.851064 (-535 4185);
WIRE 16 -1 (3725 3250)(4950 3250);
FORCEPROP 2 LAST SIG_NAME UART_BMC_1_RXD_R
J 2
(4590 3260);
DISPLAY 0.808511 (4590 3260);
WIRE 16 -1 (3725 3150)(4650 3150);
FORCEPROP 2 LAST SIG_NAME UART_BIC_DBG_RX
J 0
(3990 3160);
DISPLAY 0.808511 (3990 3160);
WIRE 16 -1 (5250 2675)(5000 2675);
WIRE 16 -1 (3725 3200)(5250 3200);
FORCEPROP 2 LAST SIG_NAME UART_BMC_5_RXD_BUF1_SW
J 2
(4815 3210);
DISPLAY 0.808511 (4815 3210);
WIRE 16 -1 (5250 3200)(5250 2675);
WIRE 16 -1 (-575 3200)(250 3200);
FORCEPROP 2 LAST SIG_NAME SPA_SIN_SW_BUF_R
J 0
(-560 3210);
DISPLAY 0.808511 (-560 3210);
WIRE 16 -1 (3675 1150)(3675 950);
WIRE 16 -1 (3675 950)(4575 950);
FORCEPROP 2 LAST SIG_NAME UART_BMC_5_TXD_BUF_R
J 0
(3815 960);
DISPLAY 0.808511 (3815 960);
WIRE 16 -1 (3350 950)(3675 950);
WIRE 16 -1 (3350 850)(4575 850);
FORCEPROP 2 LAST SIG_NAME UART_BMC_5_RXD_BUF1
J 2
(4540 860);
DISPLAY 0.808511 (4540 860);
WIRE 16 -1 (0 950)(1100 950);
FORCEPROP 2 LAST SIG_NAME UART_BMC_5_TXD_BUF1_R
J 0
(15 960);
DISPLAY 0.808511 (15 960);
WIRE 16 -1 (0 850)(850 850);
FORCEPROP 2 LAST SIG_NAME UART_BMC_5_RXD_BUF
J 0
(15 860);
DISPLAY 0.808511 (15 860);
WIRE 16 -1 (850 850)(1100 850);
WIRE 16 -1 (850 1175)(850 850);
WIRE 16 -1 (-2025 875)(-925 875);
FORCEPROP 2 LAST SIG_NAME UART_BMC_5_RXD_BUF
J 0
(-1760 885);
DISPLAY 0.808511 (-1760 885);
WIRE 16 -1 (1750 850)(3150 850);
FORCEPROP 2 LAST SIG_NAME UART_BMC_5_RXD_BUF_R
J 2
(2665 860);
DISPLAY 0.808511 (2665 860);
WIRE 16 -1 (1750 950)(3150 950);
FORCEPROP 2 LAST SIG_NAME UART_BMC_5_TXD_BUF
J 0
(1915 960);
DISPLAY 0.808511 (1915 960);
WIRE 16 -1 (75 2150)(1175 2150);
FORCEPROP 2 LAST SIG_NAME UART_BMC_5_TXD_BUF1
J 0
(215 2160);
DISPLAY 0.808511 (215 2160);
WIRE 16 -1 (1175 2050)(75 2050);
FORCEPROP 2 LAST SIG_NAME UART_BMC_5_RXD_BUF1_R
J 2
(1015 2060);
DISPLAY 0.808511 (1015 2060);
WIRE 16 3135 (4000 4775)(5625 4775);
WIRE 16 -1 (75 2100)(175 2100);
WIRE 16 -1 (175 2650)(175 2100);
WIRE 16 -1 (175 2650)(375 2650);
WIRE 16 -1 (375 2650)(375 2600);
WIRE 16 -1 (2650 3300)(3125 3300);
WIRE 16 -1 (2650 3750)(2650 3300);
WIRE 16 -1 (2650 3750)(2825 3750);
WIRE 16 -1 (2825 3750)(2825 3675);
WIRE 16 -1 (2525 4025)(3300 4025);
FORCEPROP 2 LAST SIG_NAME FM_UARTSW_MSB_N
J 0
(2540 4035);
DISPLAY 0.808511 (2540 4035);
WIRE 16 -1 (2525 4075)(3300 4075);
FORCEPROP 2 LAST SIG_NAME FM_UARTSW_LSB_N
J 0
(2540 4085);
DISPLAY 0.808511 (2540 4085);
WIRE 16 -1 (1675 4175)(575 4175);
WIRE 16 -1 (1675 4625)(1675 4175);
WIRE 16 -1 (1675 4175)(3300 4175);
FORCEPROP 2 LAST SIG_NAME SPA_SOUT_SW_BUF
J 0
(2065 4185);
DISPLAY 0.851064 (2065 4185);
WIRE 16 -1 (3000 4725)(3000 4650);
WIRE 16 -1 (2825 4725)(3000 4725);
WIRE 16 -1 (2825 4725)(2825 4275);
WIRE 16 -1 (2825 4275)(3300 4275);
WIRE 16 -1 (1525 3200)(450 3200);
WIRE 16 -1 (1525 3600)(1525 3200);
WIRE 16 -1 (3125 3200)(1525 3200);
FORCEPROP 2 LAST SIG_NAME SPA_SIN_SW_BUF
J 0
(2365 3210);
DISPLAY 0.851064 (2365 3210);
WIRE 16 -1 (2425 3100)(3125 3100);
FORCEPROP 2 LAST SIG_NAME FM_UARTSW_LSB_N
J 0
(2440 3110);
DISPLAY 0.808511 (2440 3110);
WIRE 16 -1 (2425 3050)(3125 3050);
FORCEPROP 2 LAST SIG_NAME FM_UARTSW_MSB_N
J 0
(2440 3060);
DISPLAY 0.808511 (2440 3060);
WIRE 16 -1 (3900 4125)(4825 4125);
FORCEPROP 2 LAST SIG_NAME UART_BIC_DBG_TX
J 0
(4015 4135);
DISPLAY 0.808511 (4015 4135);
WIRE 16 -1 (3900 4175)(4825 4175);
FORCEPROP 2 LAST SIG_NAME UART_BMC_5_TXD_BUF1_R
J 0
(4015 4185);
DISPLAY 0.808511 (4015 4185);
WIRE 16 -1 (3900 4225)(4825 4225);
FORCEPROP 2 LAST SIG_NAME UART_BMC_1_TXD_R
J 2
(4615 4235);
DISPLAY 0.808511 (4615 4235);
WIRE 16 3135 (4275 4850)(4275 4500);
WIRE 16 3135 (4575 4850)(4575 4500);
WIRE 16 3135 (4000 4675)(5625 4675);
WIRE 16 3135 (4000 4575)(5625 4575);
WIRE 16 3135 (3975 4875)(5650 4875);
WIRE 16 3135 (5650 4475)(5650 4875);
WIRE 16 3135 (3975 4475)(3975 4875);
WIRE 16 3135 (3975 4475)(5650 4475);
DOT 1 (1675 4175);
DOT 1 (2650 3750);
DOT 1 (1825 2150);
DOT 1 (2825 4725);
DOT 1 (-825 2050);
DOT 1 (175 2650);
DOT 1 (850 850);
DOT 1 (3675 950);
DOT 1 (2200 2050);
DOT 1 (1850 1450);
DOT 1 (1525 3200);
FORCENOTE
HIGH
(4050 4500) 0;
DISPLAY LEFT (4050 4500);
DISPLAY 1.021277 (4050 4500);
FORCENOTE
B1 CONNECTED TO A
(4625 4500) 0;
DISPLAY LEFT (4625 4500);
DISPLAY 1.021277 (4625 4500);
FORCENOTE
B0 CONNECTED TO A
(4625 4600) 0;
DISPLAY LEFT (4625 4600);
DISPLAY 1.021277 (4625 4600);
FORCENOTE
B2 CONNECTED TO A
(4625 4700) 0;
DISPLAY LEFT (4625 4700);
DISPLAY 1.021277 (4625 4700);
FORCENOTE
LOW
(4350 4500) 0;
DISPLAY LEFT (4350 4500);
DISPLAY 1.021277 (4350 4500);
FORCENOTE
LOW
(4075 4600) 0;
DISPLAY LEFT (4075 4600);
DISPLAY 1.021277 (4075 4600);
FORCENOTE
HIGH
(4050 4700) 0;
DISPLAY LEFT (4050 4700);
DISPLAY 1.021277 (4050 4700);
FORCENOTE
HIGH
(4325 4600) 0;
DISPLAY LEFT (4325 4600);
DISPLAY 1.021277 (4325 4600);
FORCENOTE
HIGH
(4325 4700) 0;
DISPLAY LEFT (4325 4700);
DISPLAY 1.021277 (4325 4700);
FORCENOTE
BMC AND TXD5/RXD5 ISOLATION BUFFER
(3975 4000) 0;
DISPLAY LEFT (3975 4000);
DISPLAY 1.021277 (3975 4000);
FORCENOTE
DEBUG HEADER SIDE
(675 2375) 0;
DISPLAY LEFT (675 2375);
DISPLAY 1.021277 (675 2375);
FORCENOTE
BMC AND TXD5/RXD5 ISOLATION BUFFER
(3975 3375) 0;
DISPLAY LEFT (3975 3375);
DISPLAY 1.021277 (3975 3375);
FORCENOTE
S1
(4375 4800) 0;
DISPLAY LEFT (4375 4800);
DISPLAY 1.021277 (4375 4800);
FORCENOTE
CONNECTOR SIDE
(-1075 3400) 0;
DISPLAY LEFT (-1075 3400);
DISPLAY 1.021277 (-1075 3400);
FORCENOTE
ISOLATION
(1200 575) 0;
DISPLAY LEFT (1200 575);
DISPLAY 1.276596 (1200 575);
FORCENOTE
RESERVED DEBUG MINI-USB
(-3450 375) 0;
DISPLAY LEFT (-3450 375);
DISPLAY 2.000000 (-3450 375);
PAINT YELLOW (-3450 375);
FORCENOTE
FUNCTION
(4625 4800) 0;
DISPLAY LEFT (4625 4800);
DISPLAY 1.021277 (4625 4800);
FORCENOTE
CONNECTOR SIDE
(-1075 4400) 0;
DISPLAY LEFT (-1075 4400);
DISPLAY 1.021277 (-1075 4400);
FORCENOTE
S2
(4100 4800) 0;
DISPLAY LEFT (4100 4800);
DISPLAY 1.021277 (4100 4800);
FORCENOTE
DEBUG HEADER SIDE
(3950 1050) 0;
DISPLAY LEFT (3950 1050);
DISPLAY 1.021277 (3950 1050);
FORCENOTE
BMC SIDE
(4000 725) 0;
DISPLAY LEFT (4000 725);
DISPLAY 1.021277 (4000 725);
FORCENOTE
OPEN-DRAIN
(1175 675) 0;
DISPLAY LEFT (1175 675);
DISPLAY 1.276596 (1175 675);
FORCENOTE
UART SWITCH
(2500 2275) 0;
DISPLAY LEFT (2500 2275);
DISPLAY 1.021277 (2500 2275);
FORCENOTE
DEBUG HEADER SIDE
(0 700) 0;
DISPLAY LEFT (0 700);
DISPLAY 1.021277 (0 700);
FORCENOTE
MUX FOR SWITCHING SYSTEM (BIOS)
(-3575 4900) 0;
DISPLAY LEFT (-3575 4900);
DISPLAY 2.000000 (-3575 4900);
PAINT YELLOW (-3575 4900);
FORCENOTE
AND BMC_DEBUG
(-3575 4750) 0;
DISPLAY LEFT (-3575 4750);
DISPLAY 2.000000 (-3575 4750);
PAINT YELLOW (-3575 4750);
FORCENOTE
BMC SIDE
(-1650 2300) 0;
DISPLAY LEFT (-1650 2300);
DISPLAY 1.021277 (-1650 2300);
FORCENOTE
UART SWITCH
(-1675 1900) 0;
DISPLAY LEFT (-1675 1900);
DISPLAY 1.021277 (-1675 1900);
FORCENOTE
RESERVED DEBUG HEADER
(-3475 1475) 0;
DISPLAY LEFT (-3475 1475);
DISPLAY 2.000000 (-3475 1475);
PAINT YELLOW (-3475 1475);
FORCENOTE
OPEN-DRAIN
(-500 1875) 0;
DISPLAY LEFT (-500 1875);
DISPLAY 1.276596 (-500 1875);
FORCENOTE
ISOLATION
(-500 1775) 0;
DISPLAY LEFT (-500 1775);
DISPLAY 1.276596 (-500 1775);
FORCENOTE
BMC SIDE
(25 1050) 0;
DISPLAY LEFT (25 1050);
DISPLAY 1.021277 (25 1050);
FORCENOTE
BMC SIDE
(2525 1900) 0;
DISPLAY LEFT (2525 1900);
DISPLAY 1.021277 (2525 1900);
FORCENOTE
ISOLATION FOR BMC TXD5/RXD5
(-3575 2675) 0;
DISPLAY LEFT (-3575 2675);
DISPLAY 2.000000 (-3575 2675);
PAINT YELLOW (-3575 2675);
QUIT
